FILE_TYPE = MACRO_DRAWING;
SET COLOR_WIRE YELLOW;
SET COLOR_PROP ORANGE;
SET COLOR_DOT WHITE;
SET COLOR_ARC YELLOW;
SET COLOR_BODY GREEN;
SET COLOR_NOTE PURPLE;
SET PROP_DISPLAY VALUE;
SET PAGE_NUMBER P261;
FORCEADD UNIVERSAL_GND..1
(-10900 1175);
FORCEPROP 3 LASTPIN (-10900 1225) SIG_NAME GND\g
J 0
(-10890 1235);
DISPLAY 0.659574 (-10890 1235);
PAINT MONO (-10890 1235);
DISPLAY INVISIBLE (-10890 1235);
FORCEPROP 2 LAST CDS_LIB logical_power
J 0
(-10900 1175);
DISPLAY INVISIBLE (-10900 1175);
FORCEPROP 1 LAST HDL_POWER GND
J 1
(-10875 1100);
DISPLAY 0.872340 (-10875 1100);
PAINT GREEN (-10875 1100);
DISPLAY INVISIBLE (-10875 1100);
FORCEPROP 1 LAST PATH I1
J 0
(-10825 1175);
DISPLAY 0.872340 (-10825 1175);
PAINT AQUA (-10825 1175);
DISPLAY INVISIBLE (-10825 1175);
FORCEADD UNIVERSAL_GND..1
(-10400 2175);
FORCEPROP 3 LASTPIN (-10400 2225) SIG_NAME GND\g
J 0
(-10390 2235);
DISPLAY 0.659574 (-10390 2235);
PAINT MONO (-10390 2235);
DISPLAY INVISIBLE (-10390 2235);
FORCEPROP 2 LAST CDS_LIB logical_power
J 0
(-10400 2175);
PAINT MONO (-10400 2175);
DISPLAY INVISIBLE (-10400 2175);
FORCEPROP 1 LAST HDL_POWER GND
J 1
(-10375 2100);
DISPLAY 0.872340 (-10375 2100);
PAINT GREEN (-10375 2100);
DISPLAY INVISIBLE (-10375 2100);
FORCEPROP 1 LAST PATH I10
J 0
(-10325 2175);
DISPLAY 0.872340 (-10325 2175);
PAINT AQUA (-10325 2175);
DISPLAY INVISIBLE (-10325 2175);
FORCEPROP 2 LAST ROOM VR_CORE0_CTRL
J 0
(-10672 2297);
DISPLAY INVISIBLE (-10672 2297);
FORCEADD Q_CAP..2
(-10225 1800);
FORCEPROP 1 LAST PART_NUMBER CH4104K1B00
J 1
(-9975 1750);
DISPLAY 0.617021 (-9975 1750);
PAINT BLUE (-9975 1750);
DISPLAY INVISIBLE (-9975 1750);
FORCEPROP 1 LAST MATERIAL X7R
J 0
(-9950 1800);
DISPLAY 0.617021 (-9950 1800);
PAINT SKYBLUE (-9950 1800);
FORCEPROP 1 LAST VOLTAGE 25V
J 0
(-10325 1750);
DISPLAY 0.617021 (-10325 1750);
PAINT SKYBLUE (-10325 1750);
FORCEPROP 1 LAST TOLERANCE 10%
J 2
(-9750 1800);
DISPLAY 0.617021 (-9750 1800);
PAINT SKYBLUE (-9750 1800);
FORCEPROP 1 LAST VALUE 0.1UF
J 2
(-10350 1750);
DISPLAY 0.617021 (-10350 1750);
PAINT SKYBLUE (-10350 1750);
FORCEPROP 1 LAST PACK_TYPE 0402
J 1
(-10050 1800);
DISPLAY 0.617021 (-10050 1800);
PAINT SKYBLUE (-10050 1800);
FORCEPROP 1 LAST LOCATION PC1346
J 1
(-10425 1800);
DISPLAY 0.617021 (-10425 1800);
PAINT AQUA (-10425 1800);
FORCEPROP 1 LASTPIN (-10325 1800) $PN 1
J 0
(-10335 1815);
DISPLAY 0.617021 (-10335 1815);
FORCEPROP 1 LASTPIN (-10125 1800) $PN 2
J 0
(-10140 1815);
DISPLAY 0.617021 (-10140 1815);
FORCEPROP 2 LAST CDS_LIB pure_quanta
J 0
(-10225 1800);
PAINT MONO (-10225 1800);
DISPLAY INVISIBLE (-10225 1800);
FORCEPROP 1 LAST PATH I11
J 0
(-10225 2000);
DISPLAY 0.978723 (-10225 2000);
PAINT WHITE (-10225 2000);
DISPLAY INVISIBLE (-10225 2000);
FORCEPROP 2 LAST $SEC 1
J 0
(-10225 2050);
DISPLAY 0.680851 (-10225 2050);
PAINT MONO (-10225 2050);
DISPLAY INVISIBLE (-10225 2050);
FORCEPROP 2 LAST CDS_SEC 1
J 0
(-10225 2050);
DISPLAY 1.021277 (-10225 2050);
DISPLAY INVISIBLE (-10225 2050);
FORCEADD ISL99390FRZTR5935..1
(-8875 1975);
FORCEPROP 1 LAST PART_NUMBER AL099390004
J 0
(-9175 2775);
DISPLAY 0.723404 (-9175 2775);
PAINT GREEN (-9175 2775);
DISPLAY INVISIBLE (-9175 2775);
FORCEPROP 2 LAST VALUE ISL99390FRZ-TR5935
J 0
(-9175 2975);
DISPLAY 0.957447 (-9175 2975);
PAINT SKYBLUE (-9175 2975);
FORCEPROP 1 LAST MATERIAL IC
J 0
(-9175 2700);
DISPLAY 0.723404 (-9175 2700);
PAINT GREEN (-9175 2700);
FORCEPROP 2 LAST PART_TYPE SMLF
J 0
(-9150 3050);
DISPLAY 1.021277 (-9150 3050);
FORCEPROP 1 LAST LOCATION PU44_P0_2
J 0
(-9175 2850);
DISPLAY 0.723404 (-9175 2850);
PAINT GREEN (-9175 2850);
FORCEPROP 2 LASTPIN (-8475 1525) $PN 2
J 0
(-8465 1535);
DISPLAY 0.680851 (-8465 1535);
PAINT MONO (-8465 1535);
FORCEPROP 2 LASTPIN (-8475 2325) $PN 33
J 0
(-8465 2335);
DISPLAY 0.680851 (-8465 2335);
PAINT MONO (-8465 2335);
FORCEPROP 2 LASTPIN (-9325 1725) $PN 31
J 2
(-9335 1735);
DISPLAY 0.680851 (-9335 1735);
PAINT MONO (-9335 1735);
FORCEPROP 2 LASTPIN (-9325 2125) $PN 35
J 2
(-9335 2135);
DISPLAY 0.680851 (-9335 2135);
PAINT MONO (-9335 2135);
FORCEPROP 2 LASTPIN (-8475 1675) $PN 6
J 0
(-8465 1685);
DISPLAY 0.680851 (-8465 1685);
PAINT MONO (-8465 1685);
FORCEPROP 2 LASTPIN (-8475 1625) $PN 41
J 0
(-8465 1635);
DISPLAY 0.680851 (-8465 1635);
PAINT MONO (-8465 1635);
FORCEPROP 2 LASTPIN (-9325 1975) $PN 38
J 2
(-9335 1985);
DISPLAY 0.680851 (-9335 1985);
PAINT MONO (-9335 1985);
FORCEPROP 2 LASTPIN (-9325 1675) $PN 37
J 2
(-9335 1685);
DISPLAY 0.680851 (-9335 1685);
PAINT MONO (-9335 1685);
FORCEPROP 2 LASTPIN (-8475 1475) $PN 5
J 0
(-8465 1485);
DISPLAY 0.680851 (-8465 1485);
PAINT MONO (-8465 1485);
FORCEPROP 2 LASTPIN (-8475 1425) $PN 7_9-20_24
J 0
(-8465 1435);
DISPLAY 0.680851 (-8465 1435);
PAINT MONO (-8465 1435);
FORCEPROP 2 LASTPIN (-8475 1375) $PN 40
J 0
(-8465 1385);
DISPLAY 0.680851 (-8465 1385);
PAINT MONO (-8465 1385);
FORCEPROP 2 LASTPIN (-8475 2075) $PN 32
J 0
(-8465 2085);
DISPLAY 0.680851 (-8465 2085);
PAINT MONO (-8465 2085);
FORCEPROP 2 LASTPIN (-9325 2625) $PN 4
J 2
(-9335 2635);
DISPLAY 0.680851 (-9335 2635);
PAINT MONO (-9335 2635);
FORCEPROP 2 LASTPIN (-9325 1375) $PN 34
J 2
(-9335 1385);
DISPLAY 0.680851 (-9335 1385);
PAINT MONO (-9335 1385);
FORCEPROP 2 LASTPIN (-9325 1875) $PN 39
J 2
(-9335 1885);
DISPLAY 0.680851 (-9335 1885);
PAINT MONO (-9335 1885);
FORCEPROP 2 LASTPIN (-8475 1975) $PN 10_19
J 0
(-8465 1985);
DISPLAY 0.680851 (-8465 1985);
PAINT MONO (-8465 1985);
FORCEPROP 2 LASTPIN (-9325 1475) $PN 36
J 2
(-9335 1485);
DISPLAY 0.680851 (-9335 1485);
PAINT MONO (-9335 1485);
FORCEPROP 2 LASTPIN (-9325 2325) $PN 3
J 2
(-9335 2335);
DISPLAY 0.680851 (-9335 2335);
PAINT MONO (-9335 2335);
FORCEPROP 2 LASTPIN (-8475 2625) $PN 25_29
J 0
(-8465 2635);
DISPLAY 0.680851 (-8465 2635);
PAINT MONO (-8465 2635);
FORCEPROP 2 LASTPIN (-8475 2575) $PN 30
J 0
(-8465 2585);
DISPLAY 0.680851 (-8465 2585);
PAINT MONO (-8465 2585);
FORCEPROP 2 LASTPIN (-8475 1725) $PN 1
J 0
(-8465 1735);
DISPLAY 0.680851 (-8465 1735);
PAINT MONO (-8465 1735);
FORCEPROP 1 LAST NEEDS_NO_SIZE TRUE
J 0
(-8875 1975);
DISPLAY 0.723404 (-8875 1975);
PAINT GREEN (-8875 1975);
DISPLAY INVISIBLE (-8875 1975);
FORCEPROP 1 LAST CDS_LMAN_SYM_OUTLINE -300,700,250,-650
J 0
(-8875 1975);
DISPLAY 0.468085 (-8875 1975);
PAINT GREEN (-8875 1975);
DISPLAY INVISIBLE (-8875 1975);
FORCEPROP 2 LAST CDS_LIB pure_quanta
J 0
(-8875 1975);
DISPLAY INVISIBLE (-8875 1975);
FORCEPROP 2 LAST SEC_TYPE 
J 0
(-9150 3100);
DISPLAY 1.021277 (-9150 3100);
DISPLAY INVISIBLE (-9150 3100);
FORCEPROP 1 LAST PATH I12
J 0
(-8875 1975);
DISPLAY 0.723404 (-8875 1975);
PAINT GREEN (-8875 1975);
DISPLAY INVISIBLE (-8875 1975);
FORCEPROP 2 LAST SEC 1
J 0
(-9150 3100);
DISPLAY 0.680851 (-9150 3100);
PAINT MONO (-9150 3100);
DISPLAY INVISIBLE (-9150 3100);
FORCEADD Q_CAP..1
(-10400 2425);
FORCEPROP 1 LAST PART_NUMBER CH5222KEB01
J 0
(-10350 2250);
DISPLAY 0.617021 (-10350 2250);
PAINT BLUE (-10350 2250);
DISPLAY INVISIBLE (-10350 2250);
FORCEPROP 1 LAST VALUE 2.2UF
J 0
(-10350 2500);
DISPLAY 0.617021 (-10350 2500);
PAINT SKYBLUE (-10350 2500);
FORCEPROP 1 LAST VOLTAGE 10V
J 0
(-10350 2450);
DISPLAY 0.617021 (-10350 2450);
PAINT SKYBLUE (-10350 2450);
FORCEPROP 1 LAST MATERIAL X6S
J 0
(-10350 2350);
DISPLAY 0.617021 (-10350 2350);
PAINT SKYBLUE (-10350 2350);
FORCEPROP 1 LAST TOLERANCE 10%
J 0
(-10350 2400);
DISPLAY 0.617021 (-10350 2400);
PAINT SKYBLUE (-10350 2400);
FORCEPROP 1 LAST PACK_TYPE C0402
J 0
(-10350 2300);
DISPLAY 0.617021 (-10350 2300);
PAINT SKYBLUE (-10350 2300);
FORCEPROP 1 LAST LOCATION PC188
J 0
(-10350 2550);
DISPLAY 0.617021 (-10350 2550);
PAINT AQUA (-10350 2550);
FORCEPROP 1 LASTPIN (-10400 2525) $PN 1
J 0
(-10390 2505);
DISPLAY 0.617021 (-10390 2505);
PAINT MONO (-10390 2505);
FORCEPROP 1 LASTPIN (-10400 2325) $PN 2
J 0
(-10390 2305);
DISPLAY 0.617021 (-10390 2305);
PAINT MONO (-10390 2305);
FORCEPROP 2 LAST CDS_LIB pure_quanta
J 0
(-10400 2425);
DISPLAY INVISIBLE (-10400 2425);
FORCEPROP 1 LAST PATH I13
J 0
(-10350 2575);
DISPLAY 0.978723 (-10350 2575);
PAINT WHITE (-10350 2575);
DISPLAY INVISIBLE (-10350 2575);
FORCEPROP 1 LAST LOCATION PC188
J 0
(-10350 2600);
DISPLAY 1.021277 (-10350 2600);
PAINT AQUA (-10350 2600);
DISPLAY INVISIBLE (-10350 2600);
FORCEPROP 0 LAST $SEC 1
J 0
(-10350 2600);
DISPLAY 0.680851 (-10350 2600);
PAINT MONO (-10350 2600);
DISPLAY INVISIBLE (-10350 2600);
FORCEPROP 0 LAST CDS_SEC 1
J 0
(-10350 2600);
DISPLAY 1.021277 (-10350 2600);
DISPLAY INVISIBLE (-10350 2600);
FORCEADD Q_RES..2
(-10400 2825);
FORCEPROP 1 LAST PART_NUMBER CS-2202FB01
J 0
(-10360 2700);
DISPLAY 0.617021 (-10360 2700);
PAINT BLUE (-10360 2700);
DISPLAY INVISIBLE (-10360 2700);
FORCEPROP 1 LAST MATERIAL CHIP
J 0
(-10360 2750);
DISPLAY 0.617021 (-10360 2750);
PAINT SKYBLUE (-10360 2750);
FORCEPROP 1 LAST WATTAGE 1/16W
J 0
(-10360 2800);
DISPLAY 0.617021 (-10360 2800);
PAINT SKYBLUE (-10360 2800);
FORCEPROP 1 LAST TOLERANCE 1%
J 0
(-10355 2850);
DISPLAY 0.617021 (-10355 2850);
PAINT SKYBLUE (-10355 2850);
FORCEPROP 1 LAST PACK_TYPE 0402LF
J 0
(-10360 2650);
DISPLAY 0.617021 (-10360 2650);
PAINT SKYBLUE (-10360 2650);
FORCEPROP 1 LAST VALUE 2.2
J 0
(-10355 2900);
DISPLAY 0.617021 (-10355 2900);
PAINT SKYBLUE (-10355 2900);
FORCEPROP 1 LAST LOCATION PR102
J 0
(-10355 2950);
DISPLAY 0.617021 (-10355 2950);
PAINT AQUA (-10355 2950);
FORCEPROP 1 LASTPIN (-10400 2925) $PN 1
J 0
(-10395 2887);
DISPLAY 0.617021 (-10395 2887);
PAINT MONO (-10395 2887);
FORCEPROP 1 LASTPIN (-10400 2725) $PN 2
J 0
(-10395 2735);
DISPLAY 0.617021 (-10395 2735);
PAINT MONO (-10395 2735);
FORCEPROP 2 LAST CDS_LIB pure_quanta
J 0
(-10400 2825);
DISPLAY INVISIBLE (-10400 2825);
FORCEPROP 1 LAST PATH I14
J 0
(-10350 3000);
DISPLAY 0.978723 (-10350 3000);
PAINT WHITE (-10350 3000);
DISPLAY INVISIBLE (-10350 3000);
FORCEPROP 1 LAST LOCATION PR102
J 0
(-10350 3000);
DISPLAY 1.021277 (-10350 3000);
PAINT AQUA (-10350 3000);
DISPLAY INVISIBLE (-10350 3000);
FORCEPROP 0 LAST $SEC 1
J 0
(-10350 3000);
DISPLAY 0.680851 (-10350 3000);
PAINT MONO (-10350 3000);
DISPLAY INVISIBLE (-10350 3000);
FORCEPROP 0 LAST CDS_SEC 1
J 0
(-10350 3000);
DISPLAY 1.021277 (-10350 3000);
DISPLAY INVISIBLE (-10350 3000);
FORCEADD UNIVERSAL_GND..1
(-9875 2675);
FORCEPROP 3 LASTPIN (-9875 2725) SIG_NAME GND\g
J 0
(-9865 2735);
DISPLAY 0.659574 (-9865 2735);
PAINT MONO (-9865 2735);
DISPLAY INVISIBLE (-9865 2735);
FORCEPROP 2 LAST CDS_LIB logical_power
J 0
(-9875 2675);
DISPLAY INVISIBLE (-9875 2675);
FORCEPROP 1 LAST HDL_POWER GND
J 1
(-9850 2600);
DISPLAY 0.872340 (-9850 2600);
PAINT GREEN (-9850 2600);
DISPLAY INVISIBLE (-9850 2600);
FORCEPROP 1 LAST PATH I15
J 0
(-9800 2675);
DISPLAY 0.872340 (-9800 2675);
PAINT AQUA (-9800 2675);
DISPLAY INVISIBLE (-9800 2675);
FORCEPROP 2 LAST ROOM VR_CORE0_CTRL
J 0
(-10147 2797);
DISPLAY INVISIBLE (-10147 2797);
FORCEADD Q_CAP..1
(-9875 2900);
FORCEPROP 1 LAST PART_NUMBER CH5222KEB01
J 0
(-9825 2825);
DISPLAY 0.638298 (-9825 2825);
DISPLAY INVISIBLE (-9825 2825);
FORCEPROP 1 LAST VOLTAGE 10V
J 0
(-9825 2975);
DISPLAY 0.638298 (-9825 2975);
FORCEPROP 1 LAST TOLERANCE 10%
J 0
(-9825 2925);
DISPLAY 0.638298 (-9825 2925);
FORCEPROP 1 LAST VALUE 2.2UF
J 0
(-9825 3025);
DISPLAY 0.638298 (-9825 3025);
FORCEPROP 1 LAST PACK_TYPE C0402
J 0
(-9825 2775);
DISPLAY 0.638298 (-9825 2775);
FORCEPROP 1 LAST MATERIAL X6S
J 0
(-9825 2875);
DISPLAY 0.638298 (-9825 2875);
FORCEPROP 1 LAST LOCATION PC2946
J 0
(-9825 3075);
DISPLAY 0.638298 (-9825 3075);
FORCEPROP 1 LASTPIN (-9875 3000) $PN 1
J 0
(-9865 2980);
DISPLAY 0.787234 (-9865 2980);
PAINT MONO (-9865 2980);
FORCEPROP 1 LASTPIN (-9875 2800) $PN 2
J 0
(-9865 2780);
DISPLAY 0.787234 (-9865 2780);
PAINT MONO (-9865 2780);
FORCEPROP 2 LAST CDS_LIB pure_quanta
J 0
(-9875 2900);
DISPLAY INVISIBLE (-9875 2900);
FORCEPROP 1 LAST PATH I16
J 0
(-9825 3050);
DISPLAY 0.978723 (-9825 3050);
PAINT WHITE (-9825 3050);
DISPLAY INVISIBLE (-9825 3050);
FORCEPROP 0 LAST $SEC 1
J 0
(-9825 3125);
DISPLAY 0.680851 (-9825 3125);
PAINT MONO (-9825 3125);
DISPLAY INVISIBLE (-9825 3125);
FORCEPROP 0 LAST CDS_SEC 1
J 0
(-9825 3125);
DISPLAY 1.021277 (-9825 3125);
DISPLAY INVISIBLE (-9825 3125);
FORCEADD VCC15..1
(-10400 3350);
FORCEPROP 1 LAST HDL_POWER PVCCFA_EHV_CPU0_PVCC
J 1
(-10400 3400);
DISPLAY 0.617021 (-10400 3400);
PAINT GREEN (-10400 3400);
FORCEPROP 2 LAST CDS_LIB logical_power
J 0
(-10400 3350);
DISPLAY INVISIBLE (-10400 3350);
FORCEPROP 1 LAST PATH I17
J 0
(-10350 3375);
DISPLAY 0.872340 (-10350 3375);
PAINT AQUA (-10350 3375);
DISPLAY INVISIBLE (-10350 3375);
FORCEADD OFFPAGE..1
(-10325 4175);
FORCEPROP 2 LAST $XR0 274 
J 0
(-10577 4175);
DISPLAY 0.638298 (-10577 4175);
PAINT MONO (-10577 4175);
FORCEPROP 2 LAST CDS_LIB standard
J 0
(-10325 4175);
DISPLAY INVISIBLE (-10325 4175);
FORCEPROP 1 LAST OFFPAGE TRUE
J 0
(-10000 4050);
DISPLAY 0.872340 (-10000 4050);
PAINT GREEN (-10000 4050);
DISPLAY INVISIBLE (-10000 4050);
FORCEPROP 1 LAST COMMENT_BODY TRUE
J 0
(-10200 4075);
DISPLAY 0.872340 (-10200 4075);
PAINT GREEN (-10200 4075);
DISPLAY INVISIBLE (-10200 4075);
FORCEPROP 2 LAST PATH I18
J 0
(-10575 4225);
DISPLAY 1.021277 (-10575 4225);
DISPLAY INVISIBLE (-10575 4225);
FORCEADD OFFPAGE..5
(-10325 4275);
FORCEPROP 2 LAST $XR1 274 
J 0
(-10700 4275);
DISPLAY 0.638298 (-10700 4275);
PAINT MONO (-10700 4275);
FORCEPROP 2 LAST $XR0 275 
J 0
(-10580 4275);
DISPLAY 0.638298 (-10580 4275);
PAINT MONO (-10580 4275);
FORCEPROP 2 LAST CDS_LIB standard
J 0
(-10325 4275);
DISPLAY INVISIBLE (-10325 4275);
FORCEPROP 1 LAST OFFPAGE TRUE
J 0
(-10000 4150);
DISPLAY 0.872340 (-10000 4150);
PAINT GREEN (-10000 4150);
DISPLAY INVISIBLE (-10000 4150);
FORCEPROP 1 LAST COMMENT_BODY TRUE
J 0
(-10225 4200);
DISPLAY 0.872340 (-10225 4200);
PAINT GREEN (-10225 4200);
DISPLAY INVISIBLE (-10225 4200);
FORCEPROP 2 LAST PATH I19
J 0
(-10575 4325);
DISPLAY 1.021277 (-10575 4325);
DISPLAY INVISIBLE (-10575 4325);
FORCEADD Q_RES..2
R 2
(-10900 1400);
FORCEPROP 1 LAST PART_NUMBER CS28872FB01
J 2
(-10940 1275);
DISPLAY 0.617021 (-10940 1275);
PAINT BLUE (-10940 1275);
DISPLAY INVISIBLE (-10940 1275);
FORCEPROP 1 LAST WATTAGE 1/16W
J 2
(-10940 1375);
DISPLAY 0.617021 (-10940 1375);
PAINT SKYBLUE (-10940 1375);
FORCEPROP 1 LAST TOLERANCE 1%
J 2
(-10945 1425);
DISPLAY 0.617021 (-10945 1425);
PAINT SKYBLUE (-10945 1425);
FORCEPROP 1 LAST VALUE 8.87K
J 2
(-10945 1475);
DISPLAY 0.617021 (-10945 1475);
PAINT SKYBLUE (-10945 1475);
FORCEPROP 1 LAST PACK_TYPE 0402LF
J 2
(-10940 1225);
DISPLAY 0.617021 (-10940 1225);
PAINT SKYBLUE (-10940 1225);
FORCEPROP 1 LAST MATERIAL EMPTY
J 2
(-10940 1325);
DISPLAY 0.617021 (-10940 1325);
PAINT RED (-10940 1325);
FORCEPROP 1 LAST LOCATION PR1707
J 2
(-10945 1525);
DISPLAY 0.617021 (-10945 1525);
PAINT AQUA (-10945 1525);
FORCEPROP 1 LASTPIN (-10900 1500) $PN 1
J 2
(-10905 1462);
DISPLAY 0.617021 (-10905 1462);
PAINT MONO (-10905 1462);
FORCEPROP 1 LASTPIN (-10900 1300) $PN 2
J 2
(-10905 1310);
DISPLAY 0.617021 (-10905 1310);
PAINT MONO (-10905 1310);
FORCEPROP 2 LAST CDS_LIB pure_quanta
J 2
(-10900 1400);
DISPLAY INVISIBLE (-10900 1400);
FORCEPROP 1 LAST PATH I2
J 2
(-10950 1575);
DISPLAY 0.978723 (-10950 1575);
PAINT WHITE (-10950 1575);
DISPLAY INVISIBLE (-10950 1575);
FORCEPROP 0 LAST $SEC 1
J 0
(-10925 1550);
DISPLAY 0.680851 (-10925 1550);
PAINT MONO (-10925 1550);
DISPLAY INVISIBLE (-10925 1550);
FORCEPROP 0 LAST CDS_SEC 1
J 0
(-10925 1550);
DISPLAY 1.021277 (-10925 1550);
DISPLAY INVISIBLE (-10925 1550);
FORCEADD UNIVERSAL_GND..1
(-11025 4500);
FORCEPROP 3 LASTPIN (-11025 4550) SIG_NAME GND\g
J 0
(-11015 4560);
DISPLAY 0.659574 (-11015 4560);
PAINT MONO (-11015 4560);
DISPLAY INVISIBLE (-11015 4560);
FORCEPROP 2 LAST CDS_LIB logical_power
J 0
(-11025 4500);
PAINT MONO (-11025 4500);
DISPLAY INVISIBLE (-11025 4500);
FORCEPROP 1 LAST HDL_POWER GND
J 1
(-11000 4425);
DISPLAY 0.872340 (-11000 4425);
PAINT GREEN (-11000 4425);
DISPLAY INVISIBLE (-11000 4425);
FORCEPROP 1 LAST PATH I20
J 0
(-10950 4500);
DISPLAY 0.872340 (-10950 4500);
PAINT AQUA (-10950 4500);
DISPLAY INVISIBLE (-10950 4500);
FORCEADD OFFPAGE..1
(-10325 4675);
FORCEPROP 2 LAST $XR2 276 
J 0
(-10817 4675);
DISPLAY 0.638298 (-10817 4675);
PAINT MONO (-10817 4675);
FORCEPROP 2 LAST $XR1 275 
J 0
(-10697 4675);
DISPLAY 0.638298 (-10697 4675);
PAINT MONO (-10697 4675);
FORCEPROP 2 LAST $XR0 274 
J 0
(-10577 4675);
DISPLAY 0.638298 (-10577 4675);
PAINT MONO (-10577 4675);
FORCEPROP 2 LAST CDS_LIB standard
J 0
(-10325 4675);
DISPLAY INVISIBLE (-10325 4675);
FORCEPROP 1 LAST OFFPAGE TRUE
J 0
(-10000 4550);
DISPLAY 0.872340 (-10000 4550);
PAINT GREEN (-10000 4550);
DISPLAY INVISIBLE (-10000 4550);
FORCEPROP 1 LAST COMMENT_BODY TRUE
J 0
(-10200 4575);
DISPLAY 0.872340 (-10200 4575);
PAINT GREEN (-10200 4575);
DISPLAY INVISIBLE (-10200 4575);
FORCEPROP 2 LAST PATH I21
J 0
(-10575 4725);
DISPLAY 1.021277 (-10575 4725);
DISPLAY INVISIBLE (-10575 4725);
FORCEADD OFFPAGE..5
(-10325 4775);
FORCEPROP 2 LAST $XR0 274 
J 0
(-10580 4775);
DISPLAY 0.638298 (-10580 4775);
PAINT MONO (-10580 4775);
FORCEPROP 2 LAST CDS_LIB standard
J 0
(-10325 4775);
DISPLAY INVISIBLE (-10325 4775);
FORCEPROP 1 LAST OFFPAGE TRUE
J 0
(-10000 4650);
DISPLAY 0.872340 (-10000 4650);
PAINT GREEN (-10000 4650);
DISPLAY INVISIBLE (-10000 4650);
FORCEPROP 1 LAST COMMENT_BODY TRUE
J 0
(-10225 4700);
DISPLAY 0.872340 (-10225 4700);
PAINT GREEN (-10225 4700);
DISPLAY INVISIBLE (-10225 4700);
FORCEPROP 2 LAST PATH I22
J 0
(-10575 4825);
DISPLAY 1.021277 (-10575 4825);
DISPLAY INVISIBLE (-10575 4825);
FORCEADD UNIVERSAL_GND..1
(-10400 4975);
FORCEPROP 3 LASTPIN (-10400 5025) SIG_NAME GND\g
J 0
(-10390 5035);
DISPLAY 0.659574 (-10390 5035);
PAINT MONO (-10390 5035);
DISPLAY INVISIBLE (-10390 5035);
FORCEPROP 2 LAST CDS_LIB logical_power
J 0
(-10400 4975);
PAINT MONO (-10400 4975);
DISPLAY INVISIBLE (-10400 4975);
FORCEPROP 1 LAST HDL_POWER GND
J 1
(-10375 4900);
DISPLAY 0.872340 (-10375 4900);
PAINT GREEN (-10375 4900);
DISPLAY INVISIBLE (-10375 4900);
FORCEPROP 1 LAST PATH I23
J 0
(-10325 4975);
DISPLAY 0.872340 (-10325 4975);
PAINT AQUA (-10325 4975);
DISPLAY INVISIBLE (-10325 4975);
FORCEPROP 2 LAST ROOM VR_CORE0_CTRL
J 0
(-10672 5097);
DISPLAY INVISIBLE (-10672 5097);
FORCEADD Q_CAP..1
(-10400 5225);
FORCEPROP 1 LAST PART_NUMBER CH5222KEB01
J 0
(-10350 5050);
DISPLAY 0.617021 (-10350 5050);
PAINT BLUE (-10350 5050);
DISPLAY INVISIBLE (-10350 5050);
FORCEPROP 1 LAST PACK_TYPE C0402
J 0
(-10350 5100);
DISPLAY 0.617021 (-10350 5100);
PAINT SKYBLUE (-10350 5100);
FORCEPROP 1 LAST MATERIAL X6S
J 0
(-10350 5150);
DISPLAY 0.617021 (-10350 5150);
PAINT SKYBLUE (-10350 5150);
FORCEPROP 1 LAST TOLERANCE 10%
J 0
(-10350 5200);
DISPLAY 0.617021 (-10350 5200);
PAINT SKYBLUE (-10350 5200);
FORCEPROP 1 LAST VALUE 2.2UF
J 0
(-10350 5300);
DISPLAY 0.617021 (-10350 5300);
PAINT SKYBLUE (-10350 5300);
FORCEPROP 1 LAST VOLTAGE 10V
J 0
(-10350 5250);
DISPLAY 0.617021 (-10350 5250);
PAINT SKYBLUE (-10350 5250);
FORCEPROP 1 LAST LOCATION PC187
J 0
(-10350 5350);
DISPLAY 0.617021 (-10350 5350);
PAINT AQUA (-10350 5350);
FORCEPROP 1 LASTPIN (-10400 5325) $PN 1
J 0
(-10390 5305);
DISPLAY 0.617021 (-10390 5305);
PAINT MONO (-10390 5305);
FORCEPROP 1 LASTPIN (-10400 5125) $PN 2
J 0
(-10390 5105);
DISPLAY 0.617021 (-10390 5105);
PAINT MONO (-10390 5105);
FORCEPROP 2 LAST CDS_LIB pure_quanta
J 0
(-10400 5225);
DISPLAY INVISIBLE (-10400 5225);
FORCEPROP 1 LAST PATH I24
J 0
(-10350 5375);
DISPLAY 0.978723 (-10350 5375);
PAINT WHITE (-10350 5375);
DISPLAY INVISIBLE (-10350 5375);
FORCEPROP 1 LAST LOCATION PC187
J 0
(-10350 5400);
DISPLAY 1.021277 (-10350 5400);
PAINT AQUA (-10350 5400);
DISPLAY INVISIBLE (-10350 5400);
FORCEPROP 0 LAST $SEC 1
J 0
(-10350 5400);
DISPLAY 0.680851 (-10350 5400);
PAINT MONO (-10350 5400);
DISPLAY INVISIBLE (-10350 5400);
FORCEPROP 0 LAST CDS_SEC 1
J 0
(-10350 5400);
DISPLAY 1.021277 (-10350 5400);
DISPLAY INVISIBLE (-10350 5400);
FORCEADD Q_CAP..2
(-10200 4600);
FORCEPROP 1 LAST PART_NUMBER CH4104K1B00
J 1
(-9950 4550);
DISPLAY 0.617021 (-9950 4550);
PAINT BLUE (-9950 4550);
DISPLAY INVISIBLE (-9950 4550);
FORCEPROP 1 LAST TOLERANCE 10%
J 2
(-9750 4600);
DISPLAY 0.617021 (-9750 4600);
PAINT SKYBLUE (-9750 4600);
FORCEPROP 1 LAST VOLTAGE 25V
J 0
(-10300 4550);
DISPLAY 0.617021 (-10300 4550);
PAINT SKYBLUE (-10300 4550);
FORCEPROP 1 LAST VALUE 0.1UF
J 2
(-10325 4550);
DISPLAY 0.617021 (-10325 4550);
PAINT SKYBLUE (-10325 4550);
FORCEPROP 1 LAST PACK_TYPE 0402
J 1
(-10025 4600);
DISPLAY 0.617021 (-10025 4600);
PAINT SKYBLUE (-10025 4600);
FORCEPROP 1 LAST MATERIAL X7R
J 0
(-9950 4600);
DISPLAY 0.617021 (-9950 4600);
PAINT SKYBLUE (-9950 4600);
FORCEPROP 1 LAST LOCATION PC1347
J 1
(-10400 4600);
DISPLAY 0.617021 (-10400 4600);
PAINT AQUA (-10400 4600);
FORCEPROP 1 LASTPIN (-10300 4600) $PN 1
J 0
(-10310 4615);
DISPLAY 0.617021 (-10310 4615);
FORCEPROP 1 LASTPIN (-10100 4600) $PN 2
J 0
(-10115 4615);
DISPLAY 0.617021 (-10115 4615);
FORCEPROP 2 LAST CDS_LIB pure_quanta
J 0
(-10200 4600);
PAINT MONO (-10200 4600);
DISPLAY INVISIBLE (-10200 4600);
FORCEPROP 1 LAST PATH I25
J 0
(-10200 4800);
DISPLAY 0.978723 (-10200 4800);
PAINT WHITE (-10200 4800);
DISPLAY INVISIBLE (-10200 4800);
FORCEPROP 2 LAST $SEC 1
J 0
(-10200 4850);
DISPLAY 0.680851 (-10200 4850);
PAINT MONO (-10200 4850);
DISPLAY INVISIBLE (-10200 4850);
FORCEPROP 2 LAST CDS_SEC 1
J 0
(-10200 4850);
DISPLAY 1.021277 (-10200 4850);
DISPLAY INVISIBLE (-10200 4850);
FORCEADD Q_RES..2
(-10400 5625);
FORCEPROP 1 LAST PART_NUMBER CS-2202FB01
J 0
(-10360 5500);
DISPLAY 0.617021 (-10360 5500);
PAINT BLUE (-10360 5500);
DISPLAY INVISIBLE (-10360 5500);
FORCEPROP 1 LAST TOLERANCE 1%
J 0
(-10355 5650);
DISPLAY 0.617021 (-10355 5650);
PAINT SKYBLUE (-10355 5650);
FORCEPROP 1 LAST WATTAGE 1/16W
J 0
(-10360 5600);
DISPLAY 0.617021 (-10360 5600);
PAINT SKYBLUE (-10360 5600);
FORCEPROP 1 LAST VALUE 2.2
J 0
(-10355 5700);
DISPLAY 0.617021 (-10355 5700);
PAINT SKYBLUE (-10355 5700);
FORCEPROP 1 LAST MATERIAL CHIP
J 0
(-10360 5550);
DISPLAY 0.617021 (-10360 5550);
PAINT SKYBLUE (-10360 5550);
FORCEPROP 1 LAST PACK_TYPE 0402LF
J 0
(-10360 5450);
DISPLAY 0.617021 (-10360 5450);
PAINT SKYBLUE (-10360 5450);
FORCEPROP 1 LAST LOCATION PR101
J 0
(-10355 5750);
DISPLAY 0.617021 (-10355 5750);
PAINT AQUA (-10355 5750);
FORCEPROP 1 LASTPIN (-10400 5725) $PN 1
J 0
(-10395 5687);
DISPLAY 0.617021 (-10395 5687);
PAINT MONO (-10395 5687);
FORCEPROP 1 LASTPIN (-10400 5525) $PN 2
J 0
(-10395 5535);
DISPLAY 0.617021 (-10395 5535);
PAINT MONO (-10395 5535);
FORCEPROP 2 LAST CDS_LIB pure_quanta
J 0
(-10400 5625);
DISPLAY INVISIBLE (-10400 5625);
FORCEPROP 1 LAST PATH I26
J 0
(-10350 5800);
DISPLAY 0.978723 (-10350 5800);
PAINT WHITE (-10350 5800);
DISPLAY INVISIBLE (-10350 5800);
FORCEPROP 1 LAST LOCATION PR101
J 0
(-10350 5800);
DISPLAY 1.021277 (-10350 5800);
PAINT AQUA (-10350 5800);
DISPLAY INVISIBLE (-10350 5800);
FORCEPROP 0 LAST $SEC 1
J 0
(-10350 5800);
DISPLAY 0.680851 (-10350 5800);
PAINT MONO (-10350 5800);
DISPLAY INVISIBLE (-10350 5800);
FORCEPROP 0 LAST CDS_SEC 1
J 0
(-10350 5800);
DISPLAY 1.021277 (-10350 5800);
DISPLAY INVISIBLE (-10350 5800);
FORCEADD VCC15..1
(-10400 6075);
FORCEPROP 1 LAST HDL_POWER PVCCFA_EHV_CPU0_PVCC
J 1
(-10400 6125);
DISPLAY 0.617021 (-10400 6125);
PAINT GREEN (-10400 6125);
FORCEPROP 2 LAST CDS_LIB logical_power
J 0
(-10400 6075);
DISPLAY INVISIBLE (-10400 6075);
FORCEPROP 1 LAST PATH I27
J 0
(-10350 6100);
DISPLAY 0.872340 (-10350 6100);
PAINT AQUA (-10350 6100);
DISPLAY INVISIBLE (-10350 6100);
FORCEADD UNIVERSAL_GND..1
(-9825 5400);
FORCEPROP 3 LASTPIN (-9825 5450) SIG_NAME GND\g
J 0
(-9815 5460);
DISPLAY 0.659574 (-9815 5460);
PAINT MONO (-9815 5460);
DISPLAY INVISIBLE (-9815 5460);
FORCEPROP 2 LAST CDS_LIB logical_power
J 0
(-9825 5400);
DISPLAY INVISIBLE (-9825 5400);
FORCEPROP 1 LAST HDL_POWER GND
J 1
(-9800 5325);
DISPLAY 0.872340 (-9800 5325);
PAINT GREEN (-9800 5325);
DISPLAY INVISIBLE (-9800 5325);
FORCEPROP 1 LAST PATH I28
J 0
(-9750 5400);
DISPLAY 0.872340 (-9750 5400);
PAINT AQUA (-9750 5400);
DISPLAY INVISIBLE (-9750 5400);
FORCEPROP 2 LAST ROOM VR_CORE0_CTRL
J 0
(-10097 5522);
DISPLAY INVISIBLE (-10097 5522);
FORCEADD Q_CAP..1
(-9825 5650);
FORCEPROP 1 LAST PART_NUMBER CH5222KEB01
J 0
(-9775 5575);
DISPLAY 0.638298 (-9775 5575);
DISPLAY INVISIBLE (-9775 5575);
FORCEPROP 1 LAST MATERIAL X6S
J 0
(-9775 5625);
DISPLAY 0.638298 (-9775 5625);
FORCEPROP 1 LAST TOLERANCE 10%
J 0
(-9775 5675);
DISPLAY 0.638298 (-9775 5675);
FORCEPROP 1 LAST VOLTAGE 10V
J 0
(-9775 5725);
DISPLAY 0.638298 (-9775 5725);
FORCEPROP 1 LAST PACK_TYPE C0402
J 0
(-9775 5525);
DISPLAY 0.638298 (-9775 5525);
FORCEPROP 1 LAST VALUE 2.2UF
J 0
(-9775 5775);
DISPLAY 0.638298 (-9775 5775);
FORCEPROP 1 LAST LOCATION PC2947
J 0
(-9775 5825);
DISPLAY 0.638298 (-9775 5825);
FORCEPROP 1 LASTPIN (-9825 5750) $PN 1
J 0
(-9815 5730);
DISPLAY 0.787234 (-9815 5730);
PAINT MONO (-9815 5730);
FORCEPROP 1 LASTPIN (-9825 5550) $PN 2
J 0
(-9815 5530);
DISPLAY 0.787234 (-9815 5530);
PAINT MONO (-9815 5530);
FORCEPROP 2 LAST CDS_LIB pure_quanta
J 0
(-9825 5650);
DISPLAY INVISIBLE (-9825 5650);
FORCEPROP 1 LAST PATH I29
J 0
(-9775 5800);
DISPLAY 0.978723 (-9775 5800);
PAINT WHITE (-9775 5800);
DISPLAY INVISIBLE (-9775 5800);
FORCEPROP 0 LAST $SEC 1
J 0
(-9775 5875);
DISPLAY 0.680851 (-9775 5875);
PAINT MONO (-9775 5875);
DISPLAY INVISIBLE (-9775 5875);
FORCEPROP 0 LAST CDS_SEC 1
J 0
(-9775 5875);
DISPLAY 1.021277 (-9775 5875);
DISPLAY INVISIBLE (-9775 5875);
FORCEADD UNIVERSAL_GND..1
(-11050 1700);
FORCEPROP 3 LASTPIN (-11050 1750) SIG_NAME GND\g
J 0
(-11040 1760);
DISPLAY 0.659574 (-11040 1760);
PAINT MONO (-11040 1760);
DISPLAY INVISIBLE (-11040 1760);
FORCEPROP 2 LAST CDS_LIB logical_power
J 0
(-11050 1700);
PAINT MONO (-11050 1700);
DISPLAY INVISIBLE (-11050 1700);
FORCEPROP 1 LAST HDL_POWER GND
J 1
(-11025 1625);
DISPLAY 0.872340 (-11025 1625);
PAINT GREEN (-11025 1625);
DISPLAY INVISIBLE (-11025 1625);
FORCEPROP 1 LAST PATH I3
J 0
(-10975 1700);
DISPLAY 0.872340 (-10975 1700);
PAINT AQUA (-10975 1700);
DISPLAY INVISIBLE (-10975 1700);
FORCEADD UNIVERSAL_GND..1
(-8225 1250);
FORCEPROP 3 LASTPIN (-8225 1300) SIG_NAME GND\g
J 0
(-8215 1310);
DISPLAY 0.659574 (-8215 1310);
PAINT MONO (-8215 1310);
DISPLAY INVISIBLE (-8215 1310);
FORCEPROP 2 LAST CDS_LIB logical_power
J 0
(-8225 1250);
PAINT MONO (-8225 1250);
DISPLAY INVISIBLE (-8225 1250);
FORCEPROP 1 LAST HDL_POWER GND
J 1
(-8200 1175);
DISPLAY 0.872340 (-8200 1175);
PAINT GREEN (-8200 1175);
DISPLAY INVISIBLE (-8200 1175);
FORCEPROP 1 LAST PATH I30
J 0
(-8150 1250);
DISPLAY 0.872340 (-8150 1250);
PAINT AQUA (-8150 1250);
DISPLAY INVISIBLE (-8150 1250);
FORCEPROP 2 LAST ROOM VR_CORE0_CTRL
J 0
(-8497 1372);
DISPLAY INVISIBLE (-8497 1372);
FORCEADD Q_RES..1
(-7300 1725);
FORCEPROP 1 LAST PART_NUMBER CS00002JB13
J 0
(-7450 1475);
DISPLAY 0.617021 (-7450 1475);
PAINT BLUE (-7450 1475);
DISPLAY INVISIBLE (-7450 1475);
FORCEPROP 1 LAST PACK_TYPE 0402LF
J 0
(-7450 1575);
DISPLAY 0.617021 (-7450 1575);
PAINT SKYBLUE (-7450 1575);
FORCEPROP 1 LAST MATERIAL CHIP
J 0
(-7450 1625);
DISPLAY 0.617021 (-7450 1625);
PAINT SKYBLUE (-7450 1625);
FORCEPROP 1 LAST WATTAGE 1/16W
J 2
(-7300 1525);
DISPLAY 0.617021 (-7300 1525);
PAINT SKYBLUE (-7300 1525);
FORCEPROP 1 LAST VALUE 0
J 2
(-7275 1775);
DISPLAY 0.617021 (-7275 1775);
PAINT SKYBLUE (-7275 1775);
FORCEPROP 1 LAST TOLERANCE 5%
J 0
(-7150 1725);
DISPLAY 0.617021 (-7150 1725);
PAINT SKYBLUE (-7150 1725);
FORCEPROP 1 LAST LOCATION PR1777
J 0
(-7525 1725);
DISPLAY 0.617021 (-7525 1725);
PAINT AQUA (-7525 1725);
FORCEPROP 1 LASTPIN (-7400 1725) $PN 1
J 0
(-7388 1737);
DISPLAY 0.617021 (-7388 1737);
FORCEPROP 1 LASTPIN (-7200 1725) $PN 2
J 0
(-7238 1737);
DISPLAY 0.617021 (-7238 1737);
FORCEPROP 2 LAST CDS_LIB pure_quanta
J 0
(-7300 1725);
PAINT MONO (-7300 1725);
DISPLAY INVISIBLE (-7300 1725);
FORCEPROP 1 LAST PATH I31
J 0
(-7350 1875);
DISPLAY 0.978723 (-7350 1875);
PAINT WHITE (-7350 1875);
DISPLAY INVISIBLE (-7350 1875);
FORCEPROP 2 LAST $SEC 1
J 0
(-7350 1925);
DISPLAY 0.680851 (-7350 1925);
PAINT MONO (-7350 1925);
DISPLAY INVISIBLE (-7350 1925);
FORCEPROP 2 LAST CDS_SEC 1
J 0
(-7350 1925);
DISPLAY 1.021277 (-7350 1925);
DISPLAY INVISIBLE (-7350 1925);
FORCEADD Q_CAP..1
(-8075 2875);
FORCEPROP 1 LAST PART_NUMBER TMP_QCH2336K1B12
J 0
(-8025 2725);
DISPLAY 0.617021 (-8025 2725);
PAINT BLUE (-8025 2725);
DISPLAY INVISIBLE (-8025 2725);
FORCEPROP 1 LAST VOLTAGE 50V
J 0
(-8025 2925);
DISPLAY 0.617021 (-8025 2925);
PAINT SKYBLUE (-8025 2925);
FORCEPROP 1 LAST MATERIAL X7R
J 0
(-8025 2825);
DISPLAY 0.617021 (-8025 2825);
PAINT SKYBLUE (-8025 2825);
FORCEPROP 1 LAST TOLERANCE 10%
J 0
(-8025 2875);
DISPLAY 0.617021 (-8025 2875);
PAINT SKYBLUE (-8025 2875);
FORCEPROP 1 LAST VALUE 3300PF
J 0
(-8025 2975);
DISPLAY 0.617021 (-8025 2975);
PAINT SKYBLUE (-8025 2975);
FORCEPROP 1 LAST PACK_TYPE 0402
J 0
(-8025 2775);
DISPLAY 0.617021 (-8025 2775);
PAINT SKYBLUE (-8025 2775);
FORCEPROP 1 LAST LOCATION PC190_P0_2
J 0
(-8025 3025);
DISPLAY 0.617021 (-8025 3025);
PAINT AQUA (-8025 3025);
FORCEPROP 1 LASTPIN (-8075 2975) $PN 1
J 0
(-8065 2955);
DISPLAY 0.617021 (-8065 2955);
PAINT MONO (-8065 2955);
FORCEPROP 1 LASTPIN (-8075 2775) $PN 2
J 0
(-8065 2755);
DISPLAY 0.617021 (-8065 2755);
PAINT MONO (-8065 2755);
FORCEPROP 2 LAST CDS_LIB pure_quanta
J 0
(-8075 2875);
DISPLAY INVISIBLE (-8075 2875);
FORCEPROP 1 LAST PATH I32
J 0
(-8025 3025);
DISPLAY 0.978723 (-8025 3025);
PAINT WHITE (-8025 3025);
DISPLAY INVISIBLE (-8025 3025);
FORCEPROP 1 LAST LOCATION PC190_P0_2
J 0
(-8025 3075);
DISPLAY 1.021277 (-8025 3075);
PAINT AQUA (-8025 3075);
DISPLAY INVISIBLE (-8025 3075);
FORCEPROP 0 LAST $SEC 1
J 0
(-8025 3075);
DISPLAY 0.680851 (-8025 3075);
PAINT MONO (-8025 3075);
DISPLAY INVISIBLE (-8025 3075);
FORCEPROP 0 LAST CDS_SEC 1
J 0
(-8025 3075);
DISPLAY 1.021277 (-8025 3075);
DISPLAY INVISIBLE (-8025 3075);
FORCEADD UNIVERSAL_GND..1
(-8225 4050);
FORCEPROP 3 LASTPIN (-8225 4100) SIG_NAME GND\g
J 0
(-8215 4110);
DISPLAY 0.659574 (-8215 4110);
PAINT MONO (-8215 4110);
DISPLAY INVISIBLE (-8215 4110);
FORCEPROP 2 LAST CDS_LIB logical_power
J 0
(-8225 4050);
PAINT MONO (-8225 4050);
DISPLAY INVISIBLE (-8225 4050);
FORCEPROP 1 LAST HDL_POWER GND
J 1
(-8200 3975);
DISPLAY 0.872340 (-8200 3975);
PAINT GREEN (-8200 3975);
DISPLAY INVISIBLE (-8200 3975);
FORCEPROP 1 LAST PATH I33
J 0
(-8150 4050);
DISPLAY 0.872340 (-8150 4050);
PAINT AQUA (-8150 4050);
DISPLAY INVISIBLE (-8150 4050);
FORCEADD Q_RES..1
(-7525 2425);
FORCEPROP 1 LAST PART_NUMBER CS-3302FB01
J 0
(-7775 2275);
DISPLAY 0.617021 (-7775 2275);
PAINT BLUE (-7775 2275);
DISPLAY INVISIBLE (-7775 2275);
FORCEPROP 1 LAST MATERIAL CHIP
J 0
(-7525 2375);
DISPLAY 0.617021 (-7525 2375);
PAINT SKYBLUE (-7525 2375);
FORCEPROP 1 LAST VALUE 3.3
J 2
(-7325 2425);
DISPLAY 0.617021 (-7325 2425);
PAINT SKYBLUE (-7325 2425);
FORCEPROP 1 LAST WATTAGE 1/16W
J 2
(-7625 2325);
DISPLAY 0.617021 (-7625 2325);
PAINT SKYBLUE (-7625 2325);
FORCEPROP 1 LAST TOLERANCE 1%
J 0
(-7300 2425);
DISPLAY 0.617021 (-7300 2425);
PAINT SKYBLUE (-7300 2425);
FORCEPROP 1 LAST PACK_TYPE 0402LF
J 0
(-7775 2375);
DISPLAY 0.617021 (-7775 2375);
PAINT SKYBLUE (-7775 2375);
FORCEPROP 1 LAST LOCATION PR1775
J 0
(-7775 2425);
DISPLAY 0.617021 (-7775 2425);
PAINT AQUA (-7775 2425);
FORCEPROP 1 LASTPIN (-7625 2425) $PN 1
J 0
(-7613 2437);
DISPLAY 0.617021 (-7613 2437);
FORCEPROP 1 LASTPIN (-7425 2425) $PN 2
J 0
(-7463 2437);
DISPLAY 0.617021 (-7463 2437);
FORCEPROP 2 LAST CDS_LIB pure_quanta
J 0
(-7525 2425);
PAINT MONO (-7525 2425);
DISPLAY INVISIBLE (-7525 2425);
FORCEPROP 1 LAST PATH I34
J 0
(-7575 2575);
DISPLAY 0.978723 (-7575 2575);
PAINT WHITE (-7575 2575);
DISPLAY INVISIBLE (-7575 2575);
FORCEPROP 2 LAST $SEC 1
J 0
(-7575 2625);
DISPLAY 0.680851 (-7575 2625);
PAINT MONO (-7575 2625);
DISPLAY INVISIBLE (-7575 2625);
FORCEPROP 2 LAST CDS_SEC 1
J 0
(-7575 2625);
DISPLAY 1.021277 (-7575 2625);
DISPLAY INVISIBLE (-7575 2625);
FORCEADD Q_CAP..1
(-7675 2875);
FORCEPROP 1 LAST PART_NUMBER CH5103KEB01
J 0
(-7625 2725);
DISPLAY 0.617021 (-7625 2725);
PAINT BLUE (-7625 2725);
DISPLAY INVISIBLE (-7625 2725);
FORCEPROP 1 LAST PACK_TYPE C0402
J 0
(-7625 2775);
DISPLAY 0.617021 (-7625 2775);
PAINT SKYBLUE (-7625 2775);
FORCEPROP 1 LAST TOLERANCE 10%
J 0
(-7625 2875);
DISPLAY 0.617021 (-7625 2875);
PAINT SKYBLUE (-7625 2875);
FORCEPROP 1 LAST MATERIAL X6S
J 0
(-7625 2825);
DISPLAY 0.617021 (-7625 2825);
PAINT SKYBLUE (-7625 2825);
FORCEPROP 1 LAST VALUE 1UF
J 0
(-7625 2975);
DISPLAY 0.617021 (-7625 2975);
PAINT SKYBLUE (-7625 2975);
FORCEPROP 1 LAST VOLTAGE 16V
J 0
(-7625 2925);
DISPLAY 0.617021 (-7625 2925);
PAINT SKYBLUE (-7625 2925);
FORCEPROP 1 LAST LOCATION PC192_P0_2
J 0
(-7625 3025);
DISPLAY 0.617021 (-7625 3025);
PAINT AQUA (-7625 3025);
FORCEPROP 1 LASTPIN (-7675 2975) $PN 1
J 0
(-7665 2955);
DISPLAY 0.617021 (-7665 2955);
PAINT MONO (-7665 2955);
FORCEPROP 1 LASTPIN (-7675 2775) $PN 2
J 0
(-7665 2755);
DISPLAY 0.617021 (-7665 2755);
PAINT MONO (-7665 2755);
FORCEPROP 2 LAST CDS_LIB pure_quanta
J 0
(-7675 2875);
DISPLAY INVISIBLE (-7675 2875);
FORCEPROP 1 LAST PATH I35
J 0
(-7625 3025);
DISPLAY 0.978723 (-7625 3025);
PAINT WHITE (-7625 3025);
DISPLAY INVISIBLE (-7625 3025);
FORCEPROP 1 LAST LOCATION PC192_P0_2
J 0
(-7625 3075);
DISPLAY 1.021277 (-7625 3075);
PAINT AQUA (-7625 3075);
DISPLAY INVISIBLE (-7625 3075);
FORCEPROP 0 LAST $SEC 1
J 0
(-7625 3075);
DISPLAY 0.680851 (-7625 3075);
PAINT MONO (-7625 3075);
DISPLAY INVISIBLE (-7625 3075);
FORCEPROP 0 LAST CDS_SEC 1
J 0
(-7625 3075);
DISPLAY 1.021277 (-7625 3075);
DISPLAY INVISIBLE (-7625 3075);
FORCEADD Q_CAP..1
(-7275 2875);
FORCEPROP 1 LAST PART_NUMBER CH6223MEA01
J 0
(-7225 2725);
DISPLAY 0.617021 (-7225 2725);
PAINT BLUE (-7225 2725);
DISPLAY INVISIBLE (-7225 2725);
FORCEPROP 1 LAST TOLERANCE 20%
J 0
(-7225 2875);
DISPLAY 0.617021 (-7225 2875);
PAINT SKYBLUE (-7225 2875);
FORCEPROP 1 LAST PACK_TYPE C0805
J 0
(-7225 2775);
DISPLAY 0.617021 (-7225 2775);
PAINT SKYBLUE (-7225 2775);
FORCEPROP 1 LAST VALUE 22UF
J 0
(-7225 2975);
DISPLAY 0.617021 (-7225 2975);
PAINT SKYBLUE (-7225 2975);
FORCEPROP 1 LAST MATERIAL X6S
J 0
(-7225 2825);
DISPLAY 0.617021 (-7225 2825);
PAINT SKYBLUE (-7225 2825);
FORCEPROP 1 LAST VOLTAGE 16V
J 0
(-7225 2925);
DISPLAY 0.617021 (-7225 2925);
PAINT SKYBLUE (-7225 2925);
FORCEPROP 1 LAST LOCATION PC196_P0_2
J 0
(-7225 3025);
DISPLAY 0.617021 (-7225 3025);
PAINT AQUA (-7225 3025);
FORCEPROP 1 LASTPIN (-7275 2975) $PN 1
J 0
(-7265 2955);
DISPLAY 0.617021 (-7265 2955);
PAINT MONO (-7265 2955);
FORCEPROP 1 LASTPIN (-7275 2775) $PN 2
J 0
(-7265 2755);
DISPLAY 0.617021 (-7265 2755);
PAINT MONO (-7265 2755);
FORCEPROP 2 LAST CDS_LIB pure_quanta
J 0
(-7275 2875);
DISPLAY INVISIBLE (-7275 2875);
FORCEPROP 1 LAST PATH I36
J 0
(-7225 3025);
DISPLAY 0.978723 (-7225 3025);
PAINT WHITE (-7225 3025);
DISPLAY INVISIBLE (-7225 3025);
FORCEPROP 1 LAST LOCATION PC196_P0_2
J 0
(-7225 3075);
DISPLAY 1.021277 (-7225 3075);
PAINT AQUA (-7225 3075);
DISPLAY INVISIBLE (-7225 3075);
FORCEPROP 0 LAST $SEC 1
J 0
(-7225 3075);
DISPLAY 0.680851 (-7225 3075);
PAINT MONO (-7225 3075);
DISPLAY INVISIBLE (-7225 3075);
FORCEPROP 0 LAST CDS_SEC 1
J 0
(-7225 3075);
DISPLAY 1.021277 (-7225 3075);
DISPLAY INVISIBLE (-7225 3075);
FORCEADD Q_CAP..1
(-6875 2875);
FORCEPROP 1 LAST PART_NUMBER CH6223MEA01
J 0
(-6825 2725);
DISPLAY 0.617021 (-6825 2725);
PAINT BLUE (-6825 2725);
DISPLAY INVISIBLE (-6825 2725);
FORCEPROP 1 LAST TOLERANCE 20%
J 0
(-6825 2875);
DISPLAY 0.617021 (-6825 2875);
PAINT SKYBLUE (-6825 2875);
FORCEPROP 1 LAST PACK_TYPE C0805
J 0
(-6825 2775);
DISPLAY 0.617021 (-6825 2775);
PAINT SKYBLUE (-6825 2775);
FORCEPROP 1 LAST MATERIAL X6S
J 0
(-6825 2825);
DISPLAY 0.617021 (-6825 2825);
PAINT SKYBLUE (-6825 2825);
FORCEPROP 1 LAST VOLTAGE 16V
J 0
(-6825 2925);
DISPLAY 0.617021 (-6825 2925);
PAINT SKYBLUE (-6825 2925);
FORCEPROP 1 LAST VALUE 22UF
J 0
(-6825 2975);
DISPLAY 0.617021 (-6825 2975);
PAINT SKYBLUE (-6825 2975);
FORCEPROP 1 LAST LOCATION PC198_P0_2
J 0
(-6825 3025);
DISPLAY 0.617021 (-6825 3025);
PAINT AQUA (-6825 3025);
FORCEPROP 1 LASTPIN (-6875 2975) $PN 1
J 0
(-6865 2955);
DISPLAY 0.617021 (-6865 2955);
PAINT MONO (-6865 2955);
FORCEPROP 1 LASTPIN (-6875 2775) $PN 2
J 0
(-6865 2755);
DISPLAY 0.617021 (-6865 2755);
PAINT MONO (-6865 2755);
FORCEPROP 2 LAST CDS_LIB pure_quanta
J 0
(-6875 2875);
DISPLAY INVISIBLE (-6875 2875);
FORCEPROP 1 LAST PATH I37
J 0
(-6825 3025);
DISPLAY 0.978723 (-6825 3025);
PAINT WHITE (-6825 3025);
DISPLAY INVISIBLE (-6825 3025);
FORCEPROP 1 LAST LOCATION PC198_P0_2
J 0
(-6825 3075);
DISPLAY 1.021277 (-6825 3075);
PAINT AQUA (-6825 3075);
DISPLAY INVISIBLE (-6825 3075);
FORCEPROP 0 LAST $SEC 1
J 0
(-6825 3075);
DISPLAY 0.680851 (-6825 3075);
PAINT MONO (-6825 3075);
DISPLAY INVISIBLE (-6825 3075);
FORCEPROP 0 LAST CDS_SEC 1
J 0
(-6825 3075);
DISPLAY 1.021277 (-6825 3075);
DISPLAY INVISIBLE (-6825 3075);
FORCEADD Q_CAP..1
R 2
(-6700 2250);
FORCEPROP 1 LAST PART_NUMBER CH4106K1B01
J 2
(-6750 2175);
DISPLAY 0.617021 (-6750 2175);
PAINT BLUE (-6750 2175);
DISPLAY INVISIBLE (-6750 2175);
FORCEPROP 1 LAST MATERIAL X7R
J 2
(-6750 2200);
DISPLAY 0.617021 (-6750 2200);
PAINT SKYBLUE (-6750 2200);
FORCEPROP 1 LAST TOLERANCE 10%
J 2
(-6750 2225);
DISPLAY 0.617021 (-6750 2225);
PAINT SKYBLUE (-6750 2225);
FORCEPROP 1 LAST VOLTAGE 50V
J 2
(-6750 2250);
DISPLAY 0.617021 (-6750 2250);
PAINT SKYBLUE (-6750 2250);
FORCEPROP 1 LAST PACK_TYPE C0402
J 2
(-6750 2150);
DISPLAY 0.617021 (-6750 2150);
PAINT SKYBLUE (-6750 2150);
FORCEPROP 1 LAST VALUE 100NF
J 2
(-6750 2275);
DISPLAY 0.617021 (-6750 2275);
PAINT SKYBLUE (-6750 2275);
FORCEPROP 1 LAST LOCATION PC194
J 2
(-6750 2325);
DISPLAY 0.617021 (-6750 2325);
PAINT AQUA (-6750 2325);
FORCEPROP 1 LASTPIN (-6700 2350) $PN 1
J 2
(-6710 2330);
DISPLAY 0.617021 (-6710 2330);
FORCEPROP 1 LASTPIN (-6700 2150) $PN 2
J 2
(-6710 2130);
DISPLAY 0.617021 (-6710 2130);
FORCEPROP 2 LAST CDS_LIB pure_quanta
J 2
(-6700 2250);
PAINT MONO (-6700 2250);
DISPLAY INVISIBLE (-6700 2250);
FORCEPROP 1 LAST PATH I38
J 2
(-6750 2400);
DISPLAY 0.978723 (-6750 2400);
PAINT WHITE (-6750 2400);
DISPLAY INVISIBLE (-6750 2400);
FORCEPROP 2 LAST $SEC 1
J 0
(-6750 2450);
DISPLAY 0.680851 (-6750 2450);
PAINT MONO (-6750 2450);
DISPLAY INVISIBLE (-6750 2450);
FORCEPROP 2 LAST CDS_SEC 1
J 0
(-6750 2450);
DISPLAY 1.021277 (-6750 2450);
DISPLAY INVISIBLE (-6750 2450);
FORCEADD Q_INDUCTOR..1
(-6450 2000);
FORCEPROP 1 LAST PART_NUMBER CV+12^0EZ03
J 0
(-6575 2110);
DISPLAY 0.617021 (-6575 2110);
PAINT BLUE (-6575 2110);
DISPLAY INVISIBLE (-6575 2110);
FORCEPROP 1 LAST MATERIAL IND
J 0
(-6575 2055);
DISPLAY 0.617021 (-6575 2055);
PAINT SKYBLUE (-6575 2055);
FORCEPROP 2 LAST PACK_TYPE SMLF
J 0
(-6575 2200);
DISPLAY 0.617021 (-6575 2200);
PAINT SKYBLUE (-6575 2200);
FORCEPROP 2 LAST VALUE 120NH/69A
J 0
(-6575 2250);
DISPLAY 0.617021 (-6575 2250);
PAINT SKYBLUE (-6575 2250);
FORCEPROP 1 LAST LOCATION PL5
J 0
(-6575 2160);
DISPLAY 0.617021 (-6575 2160);
PAINT AQUA (-6575 2160);
FORCEPROP 0 LASTPIN (-6550 1975) $PN 1
J 2
(-6560 1985);
DISPLAY 0.617021 (-6560 1985);
PAINT MONO (-6560 1985);
FORCEPROP 0 LASTPIN (-6350 1975) $PN 2
J 0
(-6340 1985);
DISPLAY 0.617021 (-6340 1985);
PAINT MONO (-6340 1985);
FORCEPROP 1 LAST NEEDS_NO_SIZE TRUE
J 0
(-6450 2000);
DISPLAY 0.468085 (-6450 2000);
PAINT GREEN (-6450 2000);
DISPLAY INVISIBLE (-6450 2000);
FORCEPROP 2 LAST CDS_LIB pure_quanta
J 0
(-6450 2000);
DISPLAY INVISIBLE (-6450 2000);
FORCEPROP 1 LAST PATH I39
J 0
(-6375 2055);
DISPLAY 0.723404 (-6375 2055);
PAINT GREEN (-6375 2055);
DISPLAY INVISIBLE (-6375 2055);
FORCEPROP 0 LAST $SEC 1
J 0
(-6575 2300);
DISPLAY 0.680851 (-6575 2300);
PAINT MONO (-6575 2300);
DISPLAY INVISIBLE (-6575 2300);
FORCEPROP 0 LAST CDS_SEC 1
J 0
(-6575 2300);
DISPLAY 1.021277 (-6575 2300);
DISPLAY INVISIBLE (-6575 2300);
FORCEADD UNIVERSAL_GND..1
(-10875 3975);
FORCEPROP 3 LASTPIN (-10875 4025) SIG_NAME GND\g
J 0
(-10865 4035);
DISPLAY 0.659574 (-10865 4035);
PAINT MONO (-10865 4035);
DISPLAY INVISIBLE (-10865 4035);
FORCEPROP 2 LAST CDS_LIB logical_power
J 0
(-10875 3975);
DISPLAY INVISIBLE (-10875 3975);
FORCEPROP 1 LAST HDL_POWER GND
J 1
(-10850 3900);
DISPLAY 0.872340 (-10850 3900);
PAINT GREEN (-10850 3900);
DISPLAY INVISIBLE (-10850 3900);
FORCEPROP 1 LAST PATH I4
J 0
(-10800 3975);
DISPLAY 0.872340 (-10800 3975);
PAINT AQUA (-10800 3975);
DISPLAY INVISIBLE (-10800 3975);
FORCEADD Q_CAP..1
(-5475 1775);
FORCEPROP 1 LAST PART_NUMBER CH622KMEA03
J 0
(-5425 1600);
DISPLAY 0.617021 (-5425 1600);
PAINT BLUE (-5425 1600);
DISPLAY INVISIBLE (-5425 1600);
FORCEPROP 1 LAST TOLERANCE 20%
J 0
(-5425 1750);
DISPLAY 0.617021 (-5425 1750);
PAINT SKYBLUE (-5425 1750);
FORCEPROP 1 LAST PACK_TYPE C0805
J 0
(-5425 1650);
DISPLAY 0.617021 (-5425 1650);
PAINT SKYBLUE (-5425 1650);
FORCEPROP 1 LAST VALUE 22UF
J 0
(-5425 1850);
DISPLAY 0.617021 (-5425 1850);
PAINT SKYBLUE (-5425 1850);
FORCEPROP 1 LAST VOLTAGE 4V
J 0
(-5425 1800);
DISPLAY 0.617021 (-5425 1800);
PAINT SKYBLUE (-5425 1800);
FORCEPROP 1 LAST MATERIAL X6S
J 0
(-5425 1700);
DISPLAY 0.617021 (-5425 1700);
PAINT SKYBLUE (-5425 1700);
FORCEPROP 1 LAST LOCATION PC203_P0_2
J 0
(-5425 1900);
DISPLAY 0.617021 (-5425 1900);
PAINT AQUA (-5425 1900);
FORCEPROP 1 LASTPIN (-5475 1875) $PN 1
J 0
(-5465 1855);
DISPLAY 0.617021 (-5465 1855);
PAINT MONO (-5465 1855);
FORCEPROP 1 LASTPIN (-5475 1675) $PN 2
J 0
(-5465 1655);
DISPLAY 0.617021 (-5465 1655);
PAINT MONO (-5465 1655);
FORCEPROP 2 LAST CDS_LIB pure_quanta
J 0
(-5475 1775);
DISPLAY INVISIBLE (-5475 1775);
FORCEPROP 1 LAST PATH I40
J 0
(-5425 1925);
DISPLAY 0.978723 (-5425 1925);
PAINT WHITE (-5425 1925);
DISPLAY INVISIBLE (-5425 1925);
FORCEPROP 1 LAST LOCATION PC203_P0_2
J 0
(-5425 1950);
DISPLAY 1.021277 (-5425 1950);
PAINT AQUA (-5425 1950);
DISPLAY INVISIBLE (-5425 1950);
FORCEPROP 0 LAST $SEC 1
J 0
(-5425 1950);
DISPLAY 0.680851 (-5425 1950);
PAINT MONO (-5425 1950);
DISPLAY INVISIBLE (-5425 1950);
FORCEPROP 0 LAST CDS_SEC 1
J 0
(-5425 1950);
DISPLAY 1.021277 (-5425 1950);
DISPLAY INVISIBLE (-5425 1950);
FORCEADD Q_CAP..1
(-5050 1775);
FORCEPROP 1 LAST PART_NUMBER CH622KMEA03
J 0
(-5000 1600);
DISPLAY 0.617021 (-5000 1600);
PAINT BLUE (-5000 1600);
DISPLAY INVISIBLE (-5000 1600);
FORCEPROP 1 LAST TOLERANCE 20%
J 0
(-5000 1750);
DISPLAY 0.617021 (-5000 1750);
PAINT SKYBLUE (-5000 1750);
FORCEPROP 1 LAST VALUE 22UF
J 0
(-5000 1850);
DISPLAY 0.617021 (-5000 1850);
PAINT SKYBLUE (-5000 1850);
FORCEPROP 1 LAST VOLTAGE 4V
J 0
(-5000 1800);
DISPLAY 0.617021 (-5000 1800);
PAINT SKYBLUE (-5000 1800);
FORCEPROP 1 LAST MATERIAL X6S
J 0
(-5000 1700);
DISPLAY 0.617021 (-5000 1700);
PAINT SKYBLUE (-5000 1700);
FORCEPROP 1 LAST PACK_TYPE C0805
J 0
(-5000 1650);
DISPLAY 0.617021 (-5000 1650);
PAINT SKYBLUE (-5000 1650);
FORCEPROP 1 LAST LOCATION PC205_P0_2
J 0
(-5000 1900);
DISPLAY 0.617021 (-5000 1900);
PAINT AQUA (-5000 1900);
FORCEPROP 1 LASTPIN (-5050 1875) $PN 1
J 0
(-5040 1855);
DISPLAY 0.617021 (-5040 1855);
PAINT MONO (-5040 1855);
FORCEPROP 1 LASTPIN (-5050 1675) $PN 2
J 0
(-5040 1655);
DISPLAY 0.617021 (-5040 1655);
PAINT MONO (-5040 1655);
FORCEPROP 2 LAST CDS_LIB pure_quanta
J 0
(-5050 1775);
DISPLAY INVISIBLE (-5050 1775);
FORCEPROP 1 LAST PATH I41
J 0
(-5000 1925);
DISPLAY 0.978723 (-5000 1925);
PAINT WHITE (-5000 1925);
DISPLAY INVISIBLE (-5000 1925);
FORCEPROP 1 LAST LOCATION PC205_P0_2
J 0
(-5000 1950);
DISPLAY 1.021277 (-5000 1950);
PAINT AQUA (-5000 1950);
DISPLAY INVISIBLE (-5000 1950);
FORCEPROP 0 LAST $SEC 1
J 0
(-5000 1950);
DISPLAY 0.680851 (-5000 1950);
PAINT MONO (-5000 1950);
DISPLAY INVISIBLE (-5000 1950);
FORCEPROP 0 LAST CDS_SEC 1
J 0
(-5000 1950);
DISPLAY 1.021277 (-5000 1950);
DISPLAY INVISIBLE (-5000 1950);
FORCEADD UNIVERSAL_GND..1
(-6275 2450);
FORCEPROP 3 LASTPIN (-6275 2500) SIG_NAME GND\g
J 0
(-6265 2510);
DISPLAY 0.659574 (-6265 2510);
PAINT MONO (-6265 2510);
DISPLAY INVISIBLE (-6265 2510);
FORCEPROP 2 LAST CDS_LIB logical_power
J 0
(-6275 2450);
PAINT MONO (-6275 2450);
DISPLAY INVISIBLE (-6275 2450);
FORCEPROP 1 LAST HDL_POWER GND
J 1
(-6250 2375);
DISPLAY 0.872340 (-6250 2375);
PAINT GREEN (-6250 2375);
DISPLAY INVISIBLE (-6250 2375);
FORCEPROP 1 LAST PATH I42
J 0
(-6200 2450);
DISPLAY 0.872340 (-6200 2450);
PAINT AQUA (-6200 2450);
DISPLAY INVISIBLE (-6200 2450);
FORCEPROP 2 LAST ROOM VR_CORE0_CTRL
J 0
(-6547 2572);
DISPLAY INVISIBLE (-6547 2572);
FORCEADD VCC15..1
(-6275 3250);
FORCEPROP 3 LASTPIN (-6275 3200) SIG_NAME SW_P12V_PVCCINFAON_CPU0_FLT\g
J 0
(-6265 3210);
DISPLAY 0.659574 (-6265 3210);
PAINT MONO (-6265 3210);
DISPLAY INVISIBLE (-6265 3210);
FORCEPROP 1 LAST HDL_POWER SW_P12V_PVCCINFAON_CPU0_FLT
J 1
(-6225 3300);
DISPLAY 0.617021 (-6225 3300);
PAINT GREEN (-6225 3300);
FORCEPROP 2 LAST CDS_LIB logical_power
J 0
(-6275 3250);
DISPLAY INVISIBLE (-6275 3250);
FORCEPROP 1 LAST PATH I43
J 0
(-6225 3275);
DISPLAY 0.872340 (-6225 3275);
PAINT AQUA (-6225 3275);
DISPLAY INVISIBLE (-6225 3275);
FORCEADD UNIVERSAL_GND..1
(-4975 4200);
FORCEPROP 3 LASTPIN (-4975 4250) SIG_NAME GND\g
J 0
(-4965 4260);
DISPLAY 0.659574 (-4965 4260);
PAINT MONO (-4965 4260);
DISPLAY INVISIBLE (-4965 4260);
FORCEPROP 2 LAST CDS_LIB logical_power
J 0
(-4975 4200);
PAINT MONO (-4975 4200);
DISPLAY INVISIBLE (-4975 4200);
FORCEPROP 1 LAST HDL_POWER GND
J 1
(-4950 4125);
DISPLAY 0.872340 (-4950 4125);
PAINT GREEN (-4950 4125);
DISPLAY INVISIBLE (-4950 4125);
FORCEPROP 1 LAST PATH I44
J 0
(-4900 4200);
DISPLAY 0.872340 (-4900 4200);
PAINT AQUA (-4900 4200);
DISPLAY INVISIBLE (-4900 4200);
FORCEPROP 2 LAST ROOM VR_CORE0_CTRL
J 0
(-5247 4322);
DISPLAY INVISIBLE (-5247 4322);
FORCEADD Q_CAP..1
(-8075 5675);
FORCEPROP 1 LAST PART_NUMBER TMP_QCH2336K1B12
J 0
(-8025 5525);
DISPLAY 0.617021 (-8025 5525);
PAINT BLUE (-8025 5525);
DISPLAY INVISIBLE (-8025 5525);
FORCEPROP 1 LAST MATERIAL X7R
J 0
(-8025 5625);
DISPLAY 0.617021 (-8025 5625);
PAINT SKYBLUE (-8025 5625);
FORCEPROP 1 LAST VOLTAGE 50V
J 0
(-8025 5725);
DISPLAY 0.617021 (-8025 5725);
PAINT SKYBLUE (-8025 5725);
FORCEPROP 1 LAST VALUE 3300PF
J 0
(-8025 5775);
DISPLAY 0.617021 (-8025 5775);
PAINT SKYBLUE (-8025 5775);
FORCEPROP 1 LAST TOLERANCE 10%
J 0
(-8025 5675);
DISPLAY 0.617021 (-8025 5675);
PAINT SKYBLUE (-8025 5675);
FORCEPROP 1 LAST PACK_TYPE 0402
J 0
(-8025 5575);
DISPLAY 0.617021 (-8025 5575);
PAINT SKYBLUE (-8025 5575);
FORCEPROP 1 LAST LOCATION PC189_P0_1
J 0
(-8025 5825);
DISPLAY 0.617021 (-8025 5825);
PAINT AQUA (-8025 5825);
FORCEPROP 1 LASTPIN (-8075 5775) $PN 1
J 0
(-8065 5755);
DISPLAY 0.617021 (-8065 5755);
PAINT MONO (-8065 5755);
FORCEPROP 1 LASTPIN (-8075 5575) $PN 2
J 0
(-8065 5555);
DISPLAY 0.617021 (-8065 5555);
PAINT MONO (-8065 5555);
FORCEPROP 2 LAST CDS_LIB pure_quanta
J 0
(-8075 5675);
DISPLAY INVISIBLE (-8075 5675);
FORCEPROP 1 LAST PATH I45
J 0
(-8025 5825);
DISPLAY 0.978723 (-8025 5825);
PAINT WHITE (-8025 5825);
DISPLAY INVISIBLE (-8025 5825);
FORCEPROP 1 LAST LOCATION PC189_P0_1
J 0
(-8025 5875);
DISPLAY 1.021277 (-8025 5875);
PAINT AQUA (-8025 5875);
DISPLAY INVISIBLE (-8025 5875);
FORCEPROP 0 LAST $SEC 1
J 0
(-8025 5875);
DISPLAY 0.680851 (-8025 5875);
PAINT MONO (-8025 5875);
DISPLAY INVISIBLE (-8025 5875);
FORCEPROP 0 LAST CDS_SEC 1
J 0
(-8025 5875);
DISPLAY 1.021277 (-8025 5875);
DISPLAY INVISIBLE (-8025 5875);
FORCEADD Q_RES..1
(-7325 4525);
FORCEPROP 1 LAST PART_NUMBER CS00002JB13
J 0
(-7400 4275);
DISPLAY 0.617021 (-7400 4275);
PAINT BLUE (-7400 4275);
DISPLAY INVISIBLE (-7400 4275);
FORCEPROP 1 LAST WATTAGE 1/16W
J 2
(-7250 4425);
DISPLAY 0.617021 (-7250 4425);
PAINT SKYBLUE (-7250 4425);
FORCEPROP 1 LAST VALUE 0
J 2
(-7325 4575);
DISPLAY 0.617021 (-7325 4575);
PAINT SKYBLUE (-7325 4575);
FORCEPROP 1 LAST TOLERANCE 5%
J 0
(-7175 4550);
DISPLAY 0.617021 (-7175 4550);
PAINT SKYBLUE (-7175 4550);
FORCEPROP 1 LAST MATERIAL CHIP
J 0
(-7400 4325);
DISPLAY 0.617021 (-7400 4325);
PAINT SKYBLUE (-7400 4325);
FORCEPROP 1 LAST PACK_TYPE 0402LF
J 0
(-7400 4375);
DISPLAY 0.617021 (-7400 4375);
PAINT SKYBLUE (-7400 4375);
FORCEPROP 1 LAST LOCATION PR1776
J 0
(-7550 4525);
DISPLAY 0.617021 (-7550 4525);
PAINT AQUA (-7550 4525);
FORCEPROP 1 LASTPIN (-7425 4525) $PN 1
J 0
(-7413 4537);
DISPLAY 0.617021 (-7413 4537);
FORCEPROP 1 LASTPIN (-7225 4525) $PN 2
J 0
(-7263 4537);
DISPLAY 0.617021 (-7263 4537);
FORCEPROP 2 LAST CDS_LIB pure_quanta
J 0
(-7325 4525);
PAINT MONO (-7325 4525);
DISPLAY INVISIBLE (-7325 4525);
FORCEPROP 1 LAST PATH I46
J 0
(-7375 4675);
DISPLAY 0.978723 (-7375 4675);
PAINT WHITE (-7375 4675);
DISPLAY INVISIBLE (-7375 4675);
FORCEPROP 2 LAST $SEC 1
J 0
(-7375 4725);
DISPLAY 0.680851 (-7375 4725);
PAINT MONO (-7375 4725);
DISPLAY INVISIBLE (-7375 4725);
FORCEPROP 2 LAST CDS_SEC 1
J 0
(-7375 4725);
DISPLAY 1.021277 (-7375 4725);
DISPLAY INVISIBLE (-7375 4725);
FORCEADD Q_RES..1
(-7525 5225);
FORCEPROP 1 LAST PART_NUMBER CS-3302FB01
J 0
(-7775 5075);
DISPLAY 0.617021 (-7775 5075);
PAINT BLUE (-7775 5075);
DISPLAY INVISIBLE (-7775 5075);
FORCEPROP 1 LAST VALUE 3.3
J 2
(-7325 5225);
DISPLAY 0.617021 (-7325 5225);
PAINT SKYBLUE (-7325 5225);
FORCEPROP 1 LAST TOLERANCE 1%
J 0
(-7300 5225);
DISPLAY 0.617021 (-7300 5225);
PAINT SKYBLUE (-7300 5225);
FORCEPROP 1 LAST WATTAGE 1/16W
J 2
(-7375 5150);
DISPLAY 0.617021 (-7375 5150);
PAINT SKYBLUE (-7375 5150);
FORCEPROP 1 LAST MATERIAL CHIP
J 0
(-7750 5175);
DISPLAY 0.617021 (-7750 5175);
PAINT SKYBLUE (-7750 5175);
FORCEPROP 1 LAST PACK_TYPE 0402LF
J 0
(-7750 5125);
DISPLAY 0.617021 (-7750 5125);
PAINT SKYBLUE (-7750 5125);
FORCEPROP 1 LAST LOCATION PR1774
J 0
(-7775 5225);
DISPLAY 0.617021 (-7775 5225);
PAINT AQUA (-7775 5225);
FORCEPROP 1 LASTPIN (-7625 5225) $PN 1
J 0
(-7613 5237);
DISPLAY 0.617021 (-7613 5237);
FORCEPROP 1 LASTPIN (-7425 5225) $PN 2
J 0
(-7463 5237);
DISPLAY 0.617021 (-7463 5237);
FORCEPROP 2 LAST CDS_LIB pure_quanta
J 0
(-7525 5225);
PAINT MONO (-7525 5225);
DISPLAY INVISIBLE (-7525 5225);
FORCEPROP 1 LAST PATH I47
J 0
(-7575 5375);
DISPLAY 0.978723 (-7575 5375);
PAINT WHITE (-7575 5375);
DISPLAY INVISIBLE (-7575 5375);
FORCEPROP 2 LAST $SEC 1
J 0
(-7575 5425);
DISPLAY 0.680851 (-7575 5425);
PAINT MONO (-7575 5425);
DISPLAY INVISIBLE (-7575 5425);
FORCEPROP 2 LAST CDS_SEC 1
J 0
(-7575 5425);
DISPLAY 1.021277 (-7575 5425);
DISPLAY INVISIBLE (-7575 5425);
FORCEADD Q_CAP..1
(-7675 5675);
FORCEPROP 1 LAST PART_NUMBER CH5103KEB01
J 0
(-7625 5525);
DISPLAY 0.617021 (-7625 5525);
PAINT BLUE (-7625 5525);
DISPLAY INVISIBLE (-7625 5525);
FORCEPROP 1 LAST VOLTAGE 16V
J 0
(-7625 5725);
DISPLAY 0.617021 (-7625 5725);
PAINT SKYBLUE (-7625 5725);
FORCEPROP 1 LAST TOLERANCE 10%
J 0
(-7625 5675);
DISPLAY 0.617021 (-7625 5675);
PAINT SKYBLUE (-7625 5675);
FORCEPROP 1 LAST PACK_TYPE C0402
J 0
(-7625 5575);
DISPLAY 0.617021 (-7625 5575);
PAINT SKYBLUE (-7625 5575);
FORCEPROP 1 LAST MATERIAL X6S
J 0
(-7625 5625);
DISPLAY 0.617021 (-7625 5625);
PAINT SKYBLUE (-7625 5625);
FORCEPROP 1 LAST VALUE 1UF
J 0
(-7625 5775);
DISPLAY 0.617021 (-7625 5775);
PAINT SKYBLUE (-7625 5775);
FORCEPROP 1 LAST LOCATION PC191_P0_1
J 0
(-7625 5825);
DISPLAY 0.617021 (-7625 5825);
PAINT AQUA (-7625 5825);
FORCEPROP 1 LASTPIN (-7675 5775) $PN 1
J 0
(-7665 5755);
DISPLAY 0.617021 (-7665 5755);
PAINT MONO (-7665 5755);
FORCEPROP 1 LASTPIN (-7675 5575) $PN 2
J 0
(-7665 5555);
DISPLAY 0.617021 (-7665 5555);
PAINT MONO (-7665 5555);
FORCEPROP 2 LAST CDS_LIB pure_quanta
J 0
(-7675 5675);
DISPLAY INVISIBLE (-7675 5675);
FORCEPROP 1 LAST PATH I48
J 0
(-7625 5825);
DISPLAY 0.978723 (-7625 5825);
PAINT WHITE (-7625 5825);
DISPLAY INVISIBLE (-7625 5825);
FORCEPROP 1 LAST LOCATION PC191_P0_1
J 0
(-7625 5875);
DISPLAY 1.021277 (-7625 5875);
PAINT AQUA (-7625 5875);
DISPLAY INVISIBLE (-7625 5875);
FORCEPROP 0 LAST $SEC 1
J 0
(-7625 5875);
DISPLAY 0.680851 (-7625 5875);
PAINT MONO (-7625 5875);
DISPLAY INVISIBLE (-7625 5875);
FORCEPROP 0 LAST CDS_SEC 1
J 0
(-7625 5875);
DISPLAY 1.021277 (-7625 5875);
DISPLAY INVISIBLE (-7625 5875);
FORCEADD Q_CAP..1
(-7275 5675);
FORCEPROP 1 LAST PART_NUMBER CH6223MEA01
J 0
(-7225 5525);
DISPLAY 0.617021 (-7225 5525);
PAINT BLUE (-7225 5525);
DISPLAY INVISIBLE (-7225 5525);
FORCEPROP 1 LAST TOLERANCE 20%
J 0
(-7225 5675);
DISPLAY 0.617021 (-7225 5675);
PAINT SKYBLUE (-7225 5675);
FORCEPROP 1 LAST VALUE 22UF
J 0
(-7225 5775);
DISPLAY 0.617021 (-7225 5775);
PAINT SKYBLUE (-7225 5775);
FORCEPROP 1 LAST MATERIAL X6S
J 0
(-7225 5625);
DISPLAY 0.617021 (-7225 5625);
PAINT SKYBLUE (-7225 5625);
FORCEPROP 1 LAST VOLTAGE 16V
J 0
(-7225 5725);
DISPLAY 0.617021 (-7225 5725);
PAINT SKYBLUE (-7225 5725);
FORCEPROP 1 LAST PACK_TYPE C0805
J 0
(-7225 5575);
DISPLAY 0.617021 (-7225 5575);
PAINT SKYBLUE (-7225 5575);
FORCEPROP 1 LAST LOCATION PC195_P0_1
J 0
(-7225 5825);
DISPLAY 0.617021 (-7225 5825);
PAINT AQUA (-7225 5825);
FORCEPROP 1 LASTPIN (-7275 5775) $PN 1
J 0
(-7265 5755);
DISPLAY 0.617021 (-7265 5755);
PAINT MONO (-7265 5755);
FORCEPROP 1 LASTPIN (-7275 5575) $PN 2
J 0
(-7265 5555);
DISPLAY 0.617021 (-7265 5555);
PAINT MONO (-7265 5555);
FORCEPROP 2 LAST CDS_LIB pure_quanta
J 0
(-7275 5675);
DISPLAY INVISIBLE (-7275 5675);
FORCEPROP 1 LAST PATH I49
J 0
(-7225 5825);
DISPLAY 0.978723 (-7225 5825);
PAINT WHITE (-7225 5825);
DISPLAY INVISIBLE (-7225 5825);
FORCEPROP 1 LAST LOCATION PC195_P0_1
J 0
(-7225 5875);
DISPLAY 1.021277 (-7225 5875);
PAINT AQUA (-7225 5875);
DISPLAY INVISIBLE (-7225 5875);
FORCEPROP 0 LAST $SEC 1
J 0
(-7225 5875);
DISPLAY 0.680851 (-7225 5875);
PAINT MONO (-7225 5875);
DISPLAY INVISIBLE (-7225 5875);
FORCEPROP 0 LAST CDS_SEC 1
J 0
(-7225 5875);
DISPLAY 1.021277 (-7225 5875);
DISPLAY INVISIBLE (-7225 5875);
FORCEADD Q_RES..2
R 2
(-10875 4200);
FORCEPROP 1 LAST PART_NUMBER CS28872FB01
J 2
(-10915 4075);
DISPLAY 0.617021 (-10915 4075);
PAINT BLUE (-10915 4075);
DISPLAY INVISIBLE (-10915 4075);
FORCEPROP 1 LAST PACK_TYPE 0402LF
J 2
(-10915 4025);
DISPLAY 0.617021 (-10915 4025);
PAINT SKYBLUE (-10915 4025);
FORCEPROP 1 LAST WATTAGE 1/16W
J 2
(-10915 4175);
DISPLAY 0.617021 (-10915 4175);
PAINT SKYBLUE (-10915 4175);
FORCEPROP 1 LAST MATERIAL EMPTY
J 2
(-10915 4125);
DISPLAY 0.617021 (-10915 4125);
PAINT RED (-10915 4125);
FORCEPROP 1 LAST TOLERANCE 1%
J 2
(-10920 4225);
DISPLAY 0.617021 (-10920 4225);
PAINT SKYBLUE (-10920 4225);
FORCEPROP 1 LAST VALUE 8.87K
J 2
(-10920 4275);
DISPLAY 0.617021 (-10920 4275);
PAINT SKYBLUE (-10920 4275);
FORCEPROP 1 LAST LOCATION PR1708
J 2
(-10920 4325);
DISPLAY 0.617021 (-10920 4325);
PAINT AQUA (-10920 4325);
FORCEPROP 1 LASTPIN (-10875 4300) $PN 1
J 2
(-10880 4262);
DISPLAY 0.617021 (-10880 4262);
PAINT MONO (-10880 4262);
FORCEPROP 1 LASTPIN (-10875 4100) $PN 2
J 2
(-10880 4110);
DISPLAY 0.617021 (-10880 4110);
PAINT MONO (-10880 4110);
FORCEPROP 2 LAST CDS_LIB pure_quanta
J 2
(-10875 4200);
DISPLAY INVISIBLE (-10875 4200);
FORCEPROP 1 LAST PATH I5
J 2
(-10925 4375);
DISPLAY 0.978723 (-10925 4375);
PAINT WHITE (-10925 4375);
DISPLAY INVISIBLE (-10925 4375);
FORCEPROP 0 LAST $SEC 1
J 0
(-10900 4350);
DISPLAY 0.680851 (-10900 4350);
PAINT MONO (-10900 4350);
DISPLAY INVISIBLE (-10900 4350);
FORCEPROP 0 LAST CDS_SEC 1
J 0
(-10900 4350);
DISPLAY 1.021277 (-10900 4350);
DISPLAY INVISIBLE (-10900 4350);
FORCEADD Q_CAP..1
(-6875 5675);
FORCEPROP 1 LAST PART_NUMBER CH6223MEA01
J 0
(-6825 5525);
DISPLAY 0.617021 (-6825 5525);
PAINT BLUE (-6825 5525);
DISPLAY INVISIBLE (-6825 5525);
FORCEPROP 1 LAST TOLERANCE 20%
J 0
(-6825 5675);
DISPLAY 0.617021 (-6825 5675);
PAINT SKYBLUE (-6825 5675);
FORCEPROP 1 LAST MATERIAL X6S
J 0
(-6825 5625);
DISPLAY 0.617021 (-6825 5625);
PAINT SKYBLUE (-6825 5625);
FORCEPROP 1 LAST VALUE 22UF
J 0
(-6825 5775);
DISPLAY 0.617021 (-6825 5775);
PAINT SKYBLUE (-6825 5775);
FORCEPROP 1 LAST VOLTAGE 16V
J 0
(-6825 5725);
DISPLAY 0.617021 (-6825 5725);
PAINT SKYBLUE (-6825 5725);
FORCEPROP 1 LAST PACK_TYPE C0805
J 0
(-6825 5575);
DISPLAY 0.617021 (-6825 5575);
PAINT SKYBLUE (-6825 5575);
FORCEPROP 1 LAST LOCATION PC197_P0_1
J 0
(-6825 5825);
DISPLAY 0.617021 (-6825 5825);
PAINT AQUA (-6825 5825);
FORCEPROP 1 LASTPIN (-6875 5775) $PN 1
J 0
(-6865 5755);
DISPLAY 0.617021 (-6865 5755);
PAINT MONO (-6865 5755);
FORCEPROP 1 LASTPIN (-6875 5575) $PN 2
J 0
(-6865 5555);
DISPLAY 0.617021 (-6865 5555);
PAINT MONO (-6865 5555);
FORCEPROP 2 LAST CDS_LIB pure_quanta
J 0
(-6875 5675);
DISPLAY INVISIBLE (-6875 5675);
FORCEPROP 1 LAST PATH I50
J 0
(-6825 5825);
DISPLAY 0.978723 (-6825 5825);
PAINT WHITE (-6825 5825);
DISPLAY INVISIBLE (-6825 5825);
FORCEPROP 1 LAST LOCATION PC197_P0_1
J 0
(-6825 5875);
DISPLAY 1.021277 (-6825 5875);
PAINT AQUA (-6825 5875);
DISPLAY INVISIBLE (-6825 5875);
FORCEPROP 0 LAST $SEC 1
J 0
(-6825 5875);
DISPLAY 0.680851 (-6825 5875);
PAINT MONO (-6825 5875);
DISPLAY INVISIBLE (-6825 5875);
FORCEPROP 0 LAST CDS_SEC 1
J 0
(-6825 5875);
DISPLAY 1.021277 (-6825 5875);
DISPLAY INVISIBLE (-6825 5875);
FORCEADD Q_CAP..1
R 2
(-6700 5050);
FORCEPROP 1 LAST PART_NUMBER CH4106K1B01
J 2
(-6750 4975);
DISPLAY 0.617021 (-6750 4975);
PAINT BLUE (-6750 4975);
DISPLAY INVISIBLE (-6750 4975);
FORCEPROP 1 LAST MATERIAL X7R
J 2
(-6750 5000);
DISPLAY 0.617021 (-6750 5000);
PAINT SKYBLUE (-6750 5000);
FORCEPROP 1 LAST TOLERANCE 10%
J 2
(-6750 5025);
DISPLAY 0.617021 (-6750 5025);
PAINT SKYBLUE (-6750 5025);
FORCEPROP 1 LAST VALUE 100NF
J 2
(-6750 5075);
DISPLAY 0.617021 (-6750 5075);
PAINT SKYBLUE (-6750 5075);
FORCEPROP 1 LAST VOLTAGE 50V
J 2
(-6750 5050);
DISPLAY 0.617021 (-6750 5050);
PAINT SKYBLUE (-6750 5050);
FORCEPROP 1 LAST PACK_TYPE C0402
J 2
(-6750 4950);
DISPLAY 0.617021 (-6750 4950);
PAINT SKYBLUE (-6750 4950);
FORCEPROP 1 LAST LOCATION PC193
J 2
(-6750 5125);
DISPLAY 0.617021 (-6750 5125);
PAINT AQUA (-6750 5125);
FORCEPROP 1 LASTPIN (-6700 5150) $PN 1
J 2
(-6710 5130);
DISPLAY 0.617021 (-6710 5130);
FORCEPROP 1 LASTPIN (-6700 4950) $PN 2
J 2
(-6710 4930);
DISPLAY 0.617021 (-6710 4930);
FORCEPROP 2 LAST CDS_LIB pure_quanta
J 2
(-6700 5050);
PAINT MONO (-6700 5050);
DISPLAY INVISIBLE (-6700 5050);
FORCEPROP 1 LAST PATH I51
J 2
(-6750 5200);
DISPLAY 0.978723 (-6750 5200);
PAINT WHITE (-6750 5200);
DISPLAY INVISIBLE (-6750 5200);
FORCEPROP 2 LAST $SEC 1
J 0
(-6750 5250);
DISPLAY 0.680851 (-6750 5250);
PAINT MONO (-6750 5250);
DISPLAY INVISIBLE (-6750 5250);
FORCEPROP 2 LAST CDS_SEC 1
J 0
(-6750 5250);
DISPLAY 1.021277 (-6750 5250);
DISPLAY INVISIBLE (-6750 5250);
FORCEADD Q_INDUCTOR..1
(-6450 4800);
FORCEPROP 1 LAST PART_NUMBER CV+12^0EZ03
J 0
(-6575 4910);
DISPLAY 0.617021 (-6575 4910);
PAINT BLUE (-6575 4910);
DISPLAY INVISIBLE (-6575 4910);
FORCEPROP 1 LAST MATERIAL IND
J 0
(-6575 4855);
DISPLAY 0.617021 (-6575 4855);
PAINT SKYBLUE (-6575 4855);
FORCEPROP 2 LAST VALUE 120NH/69A
J 0
(-6575 5050);
DISPLAY 0.617021 (-6575 5050);
PAINT SKYBLUE (-6575 5050);
FORCEPROP 2 LAST PACK_TYPE SMLF
J 0
(-6575 5000);
DISPLAY 0.617021 (-6575 5000);
PAINT SKYBLUE (-6575 5000);
FORCEPROP 1 LAST LOCATION PL4
J 0
(-6575 4960);
DISPLAY 0.617021 (-6575 4960);
PAINT AQUA (-6575 4960);
FORCEPROP 0 LASTPIN (-6550 4775) $PN 1
J 2
(-6560 4785);
DISPLAY 0.617021 (-6560 4785);
PAINT MONO (-6560 4785);
FORCEPROP 0 LASTPIN (-6350 4775) $PN 2
J 0
(-6340 4785);
DISPLAY 0.617021 (-6340 4785);
PAINT MONO (-6340 4785);
FORCEPROP 2 LAST CDS_LIB pure_quanta
J 0
(-6450 4800);
DISPLAY INVISIBLE (-6450 4800);
FORCEPROP 1 LAST NEEDS_NO_SIZE TRUE
J 0
(-6450 4800);
DISPLAY 0.468085 (-6450 4800);
PAINT GREEN (-6450 4800);
DISPLAY INVISIBLE (-6450 4800);
FORCEPROP 1 LAST PATH I52
J 0
(-6375 4855);
DISPLAY 0.723404 (-6375 4855);
PAINT GREEN (-6375 4855);
DISPLAY INVISIBLE (-6375 4855);
FORCEPROP 0 LAST $SEC 1
J 0
(-6575 5100);
DISPLAY 0.680851 (-6575 5100);
PAINT MONO (-6575 5100);
DISPLAY INVISIBLE (-6575 5100);
FORCEPROP 0 LAST CDS_SEC 1
J 0
(-6575 5100);
DISPLAY 1.021277 (-6575 5100);
DISPLAY INVISIBLE (-6575 5100);
FORCEADD UNIVERSAL_GND..1
(-6275 5250);
FORCEPROP 3 LASTPIN (-6275 5300) SIG_NAME GND\g
J 0
(-6265 5310);
DISPLAY 0.659574 (-6265 5310);
PAINT MONO (-6265 5310);
DISPLAY INVISIBLE (-6265 5310);
FORCEPROP 2 LAST CDS_LIB logical_power
J 0
(-6275 5250);
PAINT MONO (-6275 5250);
DISPLAY INVISIBLE (-6275 5250);
FORCEPROP 1 LAST HDL_POWER GND
J 1
(-6250 5175);
DISPLAY 0.872340 (-6250 5175);
PAINT GREEN (-6250 5175);
DISPLAY INVISIBLE (-6250 5175);
FORCEPROP 1 LAST PATH I53
J 0
(-6200 5250);
DISPLAY 0.872340 (-6200 5250);
PAINT AQUA (-6200 5250);
DISPLAY INVISIBLE (-6200 5250);
FORCEPROP 2 LAST ROOM VR_CORE0_CTRL
J 0
(-6547 5372);
DISPLAY INVISIBLE (-6547 5372);
FORCEADD Q_CAP..1
(-6100 4575);
FORCEPROP 1 LAST PART_NUMBER CH4106K1B01
J 0
(-6050 4400);
DISPLAY 0.617021 (-6050 4400);
PAINT BLUE (-6050 4400);
DISPLAY INVISIBLE (-6050 4400);
FORCEPROP 1 LAST VALUE 100NF
J 0
(-6050 4650);
DISPLAY 0.617021 (-6050 4650);
PAINT SKYBLUE (-6050 4650);
FORCEPROP 1 LAST VOLTAGE 50V
J 0
(-6050 4600);
DISPLAY 0.617021 (-6050 4600);
PAINT SKYBLUE (-6050 4600);
FORCEPROP 1 LAST TOLERANCE 10%
J 0
(-6050 4550);
DISPLAY 0.617021 (-6050 4550);
PAINT SKYBLUE (-6050 4550);
FORCEPROP 1 LAST PACK_TYPE C0402
J 0
(-6050 4450);
DISPLAY 0.617021 (-6050 4450);
PAINT SKYBLUE (-6050 4450);
FORCEPROP 1 LAST MATERIAL X7R
J 0
(-6050 4500);
DISPLAY 0.617021 (-6050 4500);
PAINT SKYBLUE (-6050 4500);
FORCEPROP 1 LAST LOCATION PC199_P0_1
J 0
(-6050 4700);
DISPLAY 0.617021 (-6050 4700);
PAINT AQUA (-6050 4700);
FORCEPROP 1 LASTPIN (-6100 4675) $PN 1
J 0
(-6090 4655);
DISPLAY 0.617021 (-6090 4655);
PAINT MONO (-6090 4655);
FORCEPROP 1 LASTPIN (-6100 4475) $PN 2
J 0
(-6090 4455);
DISPLAY 0.617021 (-6090 4455);
PAINT MONO (-6090 4455);
FORCEPROP 2 LAST CDS_LIB pure_quanta
J 0
(-6100 4575);
DISPLAY INVISIBLE (-6100 4575);
FORCEPROP 1 LAST PATH I54
J 0
(-6050 4725);
DISPLAY 0.978723 (-6050 4725);
PAINT WHITE (-6050 4725);
DISPLAY INVISIBLE (-6050 4725);
FORCEPROP 1 LAST LOCATION PC199_P0_1
J 0
(-6050 4750);
DISPLAY 1.021277 (-6050 4750);
PAINT AQUA (-6050 4750);
DISPLAY INVISIBLE (-6050 4750);
FORCEPROP 0 LAST $SEC 1
J 0
(-6050 4750);
DISPLAY 0.680851 (-6050 4750);
PAINT MONO (-6050 4750);
DISPLAY INVISIBLE (-6050 4750);
FORCEPROP 0 LAST CDS_SEC 1
J 0
(-6050 4750);
DISPLAY 1.021277 (-6050 4750);
DISPLAY INVISIBLE (-6050 4750);
FORCEADD VCC15..1
(-6275 6050);
FORCEPROP 3 LASTPIN (-6275 6000) SIG_NAME SW_P12V_PVCCINFAON_CPU0_FLT\g
J 0
(-6265 6010);
DISPLAY 0.659574 (-6265 6010);
PAINT MONO (-6265 6010);
DISPLAY INVISIBLE (-6265 6010);
FORCEPROP 1 LAST HDL_POWER SW_P12V_PVCCINFAON_CPU0_FLT
J 1
(-6225 6100);
DISPLAY 0.617021 (-6225 6100);
PAINT GREEN (-6225 6100);
FORCEPROP 2 LAST CDS_LIB logical_power
J 0
(-6275 6050);
DISPLAY INVISIBLE (-6275 6050);
FORCEPROP 1 LAST PATH I55
J 0
(-6225 6075);
DISPLAY 0.872340 (-6225 6075);
PAINT AQUA (-6225 6075);
DISPLAY INVISIBLE (-6225 6075);
FORCEADD Q_CAP..1
(-5700 4575);
FORCEPROP 1 LAST PART_NUMBER CH622KMEA03
J 0
(-5650 4400);
DISPLAY 0.617021 (-5650 4400);
PAINT BLUE (-5650 4400);
DISPLAY INVISIBLE (-5650 4400);
FORCEPROP 1 LAST TOLERANCE 20%
J 0
(-5650 4550);
DISPLAY 0.617021 (-5650 4550);
PAINT SKYBLUE (-5650 4550);
FORCEPROP 1 LAST VOLTAGE 4V
J 0
(-5650 4600);
DISPLAY 0.617021 (-5650 4600);
PAINT SKYBLUE (-5650 4600);
FORCEPROP 1 LAST MATERIAL X6S
J 0
(-5650 4500);
DISPLAY 0.617021 (-5650 4500);
PAINT SKYBLUE (-5650 4500);
FORCEPROP 1 LAST VALUE 22UF
J 0
(-5650 4650);
DISPLAY 0.617021 (-5650 4650);
PAINT SKYBLUE (-5650 4650);
FORCEPROP 1 LAST PACK_TYPE C0805
J 0
(-5650 4450);
DISPLAY 0.617021 (-5650 4450);
PAINT SKYBLUE (-5650 4450);
FORCEPROP 1 LAST LOCATION PC202_P0_1
J 0
(-5650 4700);
DISPLAY 0.617021 (-5650 4700);
PAINT AQUA (-5650 4700);
FORCEPROP 1 LASTPIN (-5700 4675) $PN 1
J 0
(-5690 4655);
DISPLAY 0.617021 (-5690 4655);
PAINT MONO (-5690 4655);
FORCEPROP 1 LASTPIN (-5700 4475) $PN 2
J 0
(-5690 4455);
DISPLAY 0.617021 (-5690 4455);
PAINT MONO (-5690 4455);
FORCEPROP 2 LAST CDS_LIB pure_quanta
J 0
(-5700 4575);
DISPLAY INVISIBLE (-5700 4575);
FORCEPROP 1 LAST PATH I56
J 0
(-5650 4725);
DISPLAY 0.978723 (-5650 4725);
PAINT WHITE (-5650 4725);
DISPLAY INVISIBLE (-5650 4725);
FORCEPROP 1 LAST LOCATION PC202_P0_1
J 0
(-5650 4750);
DISPLAY 1.021277 (-5650 4750);
PAINT AQUA (-5650 4750);
DISPLAY INVISIBLE (-5650 4750);
FORCEPROP 0 LAST $SEC 1
J 0
(-5650 4750);
DISPLAY 0.680851 (-5650 4750);
PAINT MONO (-5650 4750);
DISPLAY INVISIBLE (-5650 4750);
FORCEPROP 0 LAST CDS_SEC 1
J 0
(-5650 4750);
DISPLAY 1.021277 (-5650 4750);
DISPLAY INVISIBLE (-5650 4750);
FORCEADD Q_CAP..1
(-5275 4575);
FORCEPROP 1 LAST PART_NUMBER CH622KMEA03
J 0
(-5225 4400);
DISPLAY 0.617021 (-5225 4400);
PAINT BLUE (-5225 4400);
DISPLAY INVISIBLE (-5225 4400);
FORCEPROP 1 LAST TOLERANCE 20%
J 0
(-5225 4550);
DISPLAY 0.617021 (-5225 4550);
PAINT SKYBLUE (-5225 4550);
FORCEPROP 1 LAST VOLTAGE 4V
J 0
(-5225 4600);
DISPLAY 0.617021 (-5225 4600);
PAINT SKYBLUE (-5225 4600);
FORCEPROP 1 LAST VALUE 22UF
J 0
(-5225 4650);
DISPLAY 0.617021 (-5225 4650);
PAINT SKYBLUE (-5225 4650);
FORCEPROP 1 LAST MATERIAL X6S
J 0
(-5225 4500);
DISPLAY 0.617021 (-5225 4500);
PAINT SKYBLUE (-5225 4500);
FORCEPROP 1 LAST PACK_TYPE C0805
J 0
(-5225 4450);
DISPLAY 0.617021 (-5225 4450);
PAINT SKYBLUE (-5225 4450);
FORCEPROP 1 LAST LOCATION PC204_P0_1
J 0
(-5225 4700);
DISPLAY 0.617021 (-5225 4700);
PAINT AQUA (-5225 4700);
FORCEPROP 1 LASTPIN (-5275 4675) $PN 1
J 0
(-5265 4655);
DISPLAY 0.617021 (-5265 4655);
PAINT MONO (-5265 4655);
FORCEPROP 1 LASTPIN (-5275 4475) $PN 2
J 0
(-5265 4455);
DISPLAY 0.617021 (-5265 4455);
PAINT MONO (-5265 4455);
FORCEPROP 2 LAST CDS_LIB pure_quanta
J 0
(-5275 4575);
DISPLAY INVISIBLE (-5275 4575);
FORCEPROP 1 LAST PATH I57
J 0
(-5225 4725);
DISPLAY 0.978723 (-5225 4725);
PAINT WHITE (-5225 4725);
DISPLAY INVISIBLE (-5225 4725);
FORCEPROP 1 LAST LOCATION PC204_P0_1
J 0
(-5225 4750);
DISPLAY 1.021277 (-5225 4750);
PAINT AQUA (-5225 4750);
DISPLAY INVISIBLE (-5225 4750);
FORCEPROP 0 LAST $SEC 1
J 0
(-5225 4750);
DISPLAY 0.680851 (-5225 4750);
PAINT MONO (-5225 4750);
DISPLAY INVISIBLE (-5225 4750);
FORCEPROP 0 LAST CDS_SEC 1
J 0
(-5225 4750);
DISPLAY 1.021277 (-5225 4750);
DISPLAY INVISIBLE (-5225 4750);
FORCEADD VCC15..1
(-4975 4975);
FORCEPROP 3 LASTPIN (-4975 4925) SIG_NAME PVCCINFAON_CPU0\g
J 0
(-4965 4935);
DISPLAY 0.659574 (-4965 4935);
PAINT MONO (-4965 4935);
DISPLAY INVISIBLE (-4965 4935);
FORCEPROP 1 LAST HDL_POWER PVCCINFAON_CPU0
J 1
(-4975 5025);
DISPLAY 0.617021 (-4975 5025);
PAINT GREEN (-4975 5025);
FORCEPROP 2 LAST CDS_LIB logical_power
J 0
(-4975 4975);
DISPLAY INVISIBLE (-4975 4975);
FORCEPROP 1 LAST PATH I58
J 0
(-4925 5000);
DISPLAY 0.872340 (-4925 5000);
PAINT AQUA (-4925 5000);
DISPLAY INVISIBLE (-4925 5000);
FORCEADD GND..1
(-5025 5650);
FORCEPROP 3 LASTPIN (-5025 5700) SIG_NAME GND\g
J 0
(-5015 5710);
DISPLAY 0.659574 (-5015 5710);
PAINT MONO (-5015 5710);
DISPLAY INVISIBLE (-5015 5710);
FORCEPROP 2 LAST CDS_LIB logical_power
J 0
(-5025 5650);
DISPLAY INVISIBLE (-5025 5650);
FORCEPROP 1 LAST SIZE 1B
J 0
(-4950 5600);
DISPLAY 0.872340 (-4950 5600);
PAINT AQUA (-4950 5600);
DISPLAY INVISIBLE (-4950 5600);
FORCEPROP 1 LAST HDL_POWER GND
J 0
(-5025 5800);
DISPLAY 0.872340 (-5025 5800);
PAINT GREEN (-5025 5800);
DISPLAY INVISIBLE (-5025 5800);
FORCEPROP 1 LAST PATH I59
J 0
(-4950 5650);
DISPLAY 0.872340 (-4950 5650);
PAINT AQUA (-4950 5650);
DISPLAY INVISIBLE (-4950 5650);
FORCEADD OFFPAGE..1
(-10325 1375);
FORCEPROP 2 LAST $XR0 274 
J 0
(-10577 1375);
DISPLAY 0.638298 (-10577 1375);
PAINT MONO (-10577 1375);
FORCEPROP 2 LAST CDS_LIB standard
J 0
(-10325 1375);
DISPLAY INVISIBLE (-10325 1375);
FORCEPROP 1 LAST OFFPAGE TRUE
J 0
(-10000 1250);
DISPLAY 0.872340 (-10000 1250);
PAINT GREEN (-10000 1250);
DISPLAY INVISIBLE (-10000 1250);
FORCEPROP 1 LAST COMMENT_BODY TRUE
J 0
(-10200 1275);
DISPLAY 0.872340 (-10200 1275);
PAINT GREEN (-10200 1275);
DISPLAY INVISIBLE (-10200 1275);
FORCEPROP 2 LAST PATH I6
J 0
(-10575 1425);
DISPLAY 1.021277 (-10575 1425);
DISPLAY INVISIBLE (-10575 1425);
FORCEADD Q_CAP..1
(-5025 5900);
FORCEPROP 1 LAST PART_NUMBER CH4106K1B01
J 0
(-4975 5750);
DISPLAY 0.787234 (-4975 5750);
DISPLAY INVISIBLE (-4975 5750);
FORCEPROP 1 LAST PACK_TYPE C0402
J 0
(-4975 5700);
DISPLAY 0.787234 (-4975 5700);
FORCEPROP 1 LAST VALUE 100NF
J 0
(-4975 5950);
DISPLAY 0.787234 (-4975 5950);
FORCEPROP 1 LAST MATERIAL X7R
J 0
(-4975 5800);
DISPLAY 0.787234 (-4975 5800);
FORCEPROP 1 LAST VOLTAGE 50V
J 0
(-4975 5900);
DISPLAY 0.787234 (-4975 5900);
FORCEPROP 1 LAST TOLERANCE 10%
J 0
(-4975 5850);
DISPLAY 0.787234 (-4975 5850);
FORCEPROP 1 LAST LOCATION PC1655
J 0
(-4975 6000);
DISPLAY 0.787234 (-4975 6000);
FORCEPROP 1 LASTPIN (-5025 6000) $PN 1
J 0
(-5015 5980);
DISPLAY 0.787234 (-5015 5980);
PAINT MONO (-5015 5980);
FORCEPROP 1 LASTPIN (-5025 5800) $PN 2
J 0
(-5015 5780);
DISPLAY 0.787234 (-5015 5780);
PAINT MONO (-5015 5780);
FORCEPROP 2 LAST CDS_LIB pure_quanta
J 0
(-5025 5900);
DISPLAY INVISIBLE (-5025 5900);
FORCEPROP 1 LAST PATH I60
J 0
(-4975 6050);
DISPLAY 0.978723 (-4975 6050);
PAINT WHITE (-4975 6050);
DISPLAY INVISIBLE (-4975 6050);
FORCEPROP 0 LAST $SEC 1
J 0
(-4975 6050);
DISPLAY 0.680851 (-4975 6050);
PAINT MONO (-4975 6050);
DISPLAY INVISIBLE (-4975 6050);
FORCEPROP 0 LAST CDS_SEC 1
J 0
(-4975 6050);
DISPLAY 1.021277 (-4975 6050);
DISPLAY INVISIBLE (-4975 6050);
FORCEADD VCC15..1
(-5025 6275);
FORCEPROP 3 LASTPIN (-5025 6225) SIG_NAME P12V_AUX\g
J 0
(-5015 6235);
DISPLAY 0.659574 (-5015 6235);
PAINT MONO (-5015 6235);
DISPLAY INVISIBLE (-5015 6235);
FORCEPROP 1 LAST HDL_POWER P12V_AUX
J 1
(-5025 6325);
DISPLAY 0.617021 (-5025 6325);
PAINT GREEN (-5025 6325);
FORCEPROP 2 LAST CDS_LIB logical_power
J 0
(-5025 6275);
DISPLAY INVISIBLE (-5025 6275);
FORCEPROP 1 LAST PATH I61
J 0
(-4975 6300);
DISPLAY 0.872340 (-4975 6300);
PAINT AQUA (-4975 6300);
DISPLAY INVISIBLE (-4975 6300);
FORCEADD Q_INDUCTOR..1
(-4600 6125);
FORCEPROP 1 LAST PART_NUMBER CV+10G0MZ04
J 0
(-4725 6200);
DISPLAY 0.617021 (-4725 6200);
PAINT BLUE (-4725 6200);
DISPLAY INVISIBLE (-4725 6200);
FORCEPROP 2 LAST PACK_TYPE SMLF
J 0
(-4725 6350);
DISPLAY 0.617021 (-4725 6350);
PAINT SKYBLUE (-4725 6350);
FORCEPROP 2 LAST VALUE 100NH/16A
J 0
(-4725 6300);
DISPLAY 0.617021 (-4725 6300);
PAINT SKYBLUE (-4725 6300);
FORCEPROP 1 LAST MATERIAL IND
J 0
(-4725 6250);
DISPLAY 0.617021 (-4725 6250);
PAINT SKYBLUE (-4725 6250);
FORCEPROP 1 LAST LOCATION PL6
J 0
(-4900 6100);
DISPLAY 0.617021 (-4900 6100);
PAINT AQUA (-4900 6100);
FORCEPROP 0 LASTPIN (-4700 6100) $PN 1
J 2
(-4710 6110);
DISPLAY 0.617021 (-4710 6110);
PAINT MONO (-4710 6110);
FORCEPROP 0 LASTPIN (-4500 6100) $PN 2
J 0
(-4490 6110);
DISPLAY 0.617021 (-4490 6110);
PAINT MONO (-4490 6110);
FORCEPROP 1 LAST NEEDS_NO_SIZE TRUE
J 0
(-4600 6125);
DISPLAY 0.468085 (-4600 6125);
PAINT GREEN (-4600 6125);
DISPLAY INVISIBLE (-4600 6125);
FORCEPROP 2 LAST CDS_LIB pure_quanta
J 0
(-4600 6125);
DISPLAY INVISIBLE (-4600 6125);
FORCEPROP 1 LAST PATH I62
J 0
(-4525 6180);
DISPLAY 0.723404 (-4525 6180);
PAINT GREEN (-4525 6180);
DISPLAY INVISIBLE (-4525 6180);
FORCEPROP 1 LAST LOCATION PL6
J 0
(-4625 6225);
DISPLAY 1.021277 (-4625 6225);
PAINT AQUA (-4625 6225);
DISPLAY INVISIBLE (-4625 6225);
FORCEPROP 0 LAST $SEC 1
J 0
(-4625 6225);
DISPLAY 0.680851 (-4625 6225);
PAINT MONO (-4625 6225);
DISPLAY INVISIBLE (-4625 6225);
FORCEPROP 0 LAST CDS_SEC 1
J 0
(-4625 6225);
DISPLAY 1.021277 (-4625 6225);
DISPLAY INVISIBLE (-4625 6225);
FORCEADD Q_RES..2
(-4575 1775);
FORCEPROP 1 LAST PART_NUMBER CS14992FB06
J 0
(-4535 1650);
DISPLAY 0.617021 (-4535 1650);
PAINT BLUE (-4535 1650);
DISPLAY INVISIBLE (-4535 1650);
FORCEPROP 1 LAST TOLERANCE 1%
J 0
(-4530 1800);
DISPLAY 0.617021 (-4530 1800);
PAINT SKYBLUE (-4530 1800);
FORCEPROP 1 LAST MATERIAL CHIP
J 0
(-4535 1700);
DISPLAY 0.617021 (-4535 1700);
PAINT SKYBLUE (-4535 1700);
FORCEPROP 1 LAST WATTAGE 1/16W
J 0
(-4535 1750);
DISPLAY 0.617021 (-4535 1750);
PAINT SKYBLUE (-4535 1750);
FORCEPROP 1 LAST PACK_TYPE 0402LF
J 0
(-4535 1600);
DISPLAY 0.617021 (-4535 1600);
PAINT SKYBLUE (-4535 1600);
FORCEPROP 1 LAST VALUE 499
J 0
(-4530 1850);
DISPLAY 0.617021 (-4530 1850);
PAINT SKYBLUE (-4530 1850);
FORCEPROP 1 LAST LOCATION PR4226
J 0
(-4530 1900);
DISPLAY 0.617021 (-4530 1900);
PAINT AQUA (-4530 1900);
FORCEPROP 1 LASTPIN (-4575 1875) $PN 1
J 0
(-4570 1837);
DISPLAY 0.787234 (-4570 1837);
PAINT MONO (-4570 1837);
FORCEPROP 1 LASTPIN (-4575 1675) $PN 2
J 0
(-4570 1685);
DISPLAY 0.787234 (-4570 1685);
PAINT MONO (-4570 1685);
FORCEPROP 2 LAST BOM_COST VR_PCH
J 0
(-4525 1950);
DISPLAY 0.680851 (-4525 1950);
DISPLAY INVISIBLE (-4525 1950);
FORCEPROP 2 LAST CDS_LIB pure_quanta
J 0
(-4575 1775);
DISPLAY INVISIBLE (-4575 1775);
FORCEPROP 1 LAST PATH I63
J 0
(-4525 1950);
DISPLAY 0.978723 (-4525 1950);
PAINT WHITE (-4525 1950);
DISPLAY INVISIBLE (-4525 1950);
FORCEPROP 0 LAST $SEC 1
J 0
(-4525 1950);
DISPLAY 0.680851 (-4525 1950);
PAINT MONO (-4525 1950);
DISPLAY INVISIBLE (-4525 1950);
FORCEPROP 0 LAST CDS_SEC 1
J 0
(-4525 1950);
DISPLAY 1.021277 (-4525 1950);
DISPLAY INVISIBLE (-4525 1950);
FORCEADD UNIVERSAL_GND..1
(-4250 1400);
FORCEPROP 3 LASTPIN (-4250 1450) SIG_NAME GND\g
J 0
(-4240 1460);
DISPLAY 0.659574 (-4240 1460);
PAINT MONO (-4240 1460);
DISPLAY INVISIBLE (-4240 1460);
FORCEPROP 2 LAST CDS_LIB logical_power
J 0
(-4250 1400);
PAINT MONO (-4250 1400);
DISPLAY INVISIBLE (-4250 1400);
FORCEPROP 1 LAST HDL_POWER GND
J 1
(-4225 1325);
DISPLAY 0.872340 (-4225 1325);
PAINT GREEN (-4225 1325);
DISPLAY INVISIBLE (-4225 1325);
FORCEPROP 1 LAST PATH I64
J 0
(-4175 1400);
DISPLAY 0.872340 (-4175 1400);
PAINT AQUA (-4175 1400);
DISPLAY INVISIBLE (-4175 1400);
FORCEPROP 2 LAST ROOM VR_CORE0_CTRL
J 0
(-4522 1522);
DISPLAY INVISIBLE (-4522 1522);
FORCEADD VCC15..1
(-4250 2150);
FORCEPROP 3 LASTPIN (-4250 2100) SIG_NAME PVCCINFAON_CPU0\g
J 0
(-4240 2110);
DISPLAY 0.659574 (-4240 2110);
PAINT MONO (-4240 2110);
DISPLAY INVISIBLE (-4240 2110);
FORCEPROP 1 LAST HDL_POWER PVCCINFAON_CPU0
J 1
(-4250 2200);
DISPLAY 0.617021 (-4250 2200);
PAINT GREEN (-4250 2200);
FORCEPROP 2 LAST CDS_LIB logical_power
J 0
(-4250 2150);
DISPLAY INVISIBLE (-4250 2150);
FORCEPROP 1 LAST PATH I65
J 0
(-4200 2175);
DISPLAY 0.872340 (-4200 2175);
PAINT AQUA (-4200 2175);
DISPLAY INVISIBLE (-4200 2175);
FORCEADD Q_CAPP..1
(-4325 3125);
FORCEPROP 1 LAST PART_NUMBER CC7560JMD16
J 0
(-4275 2925);
DISPLAY 0.617021 (-4275 2925);
PAINT BLUE (-4275 2925);
DISPLAY INVISIBLE (-4275 2925);
FORCEPROP 1 LAST PACK_TYPE THLF
J 0
(-4275 2975);
DISPLAY 0.617021 (-4275 2975);
PAINT SKYBLUE (-4275 2975);
FORCEPROP 1 LAST VALUE 560UF
J 0
(-4275 3175);
DISPLAY 0.617021 (-4275 3175);
PAINT SKYBLUE (-4275 3175);
FORCEPROP 1 LAST TOLERANCE 20%
J 0
(-4275 3125);
DISPLAY 0.617021 (-4275 3125);
PAINT SKYBLUE (-4275 3125);
FORCEPROP 1 LAST MATERIAL OSCON
J 0
(-4275 3025);
DISPLAY 0.617021 (-4275 3025);
PAINT SKYBLUE (-4275 3025);
FORCEPROP 1 LAST VOLTAGE 2.5V
J 0
(-4275 3075);
DISPLAY 0.617021 (-4275 3075);
PAINT SKYBLUE (-4275 3075);
FORCEPROP 1 LAST LOCATION PC1574
J 0
(-4275 3225);
DISPLAY 0.617021 (-4275 3225);
PAINT AQUA (-4275 3225);
FORCEPROP 1 LASTPIN (-4325 3225) $PN 1
J 0
(-4315 3210);
DISPLAY 0.617021 (-4315 3210);
PAINT MONO (-4315 3210);
FORCEPROP 1 LASTPIN (-4325 3025) $PN 2
J 0
(-4315 3010);
DISPLAY 0.617021 (-4315 3010);
PAINT MONO (-4315 3010);
FORCEPROP 2 LAST CDS_LIB pure_quanta
J 0
(-4325 3125);
DISPLAY INVISIBLE (-4325 3125);
FORCEPROP 1 LAST PATH I66
J 0
(-4275 3275);
DISPLAY 0.978723 (-4275 3275);
DISPLAY INVISIBLE (-4275 3275);
FORCEPROP 2 LAST $SEC 1
J 0
(-4275 3325);
DISPLAY 0.680851 (-4275 3325);
PAINT MONO (-4275 3325);
DISPLAY INVISIBLE (-4275 3325);
FORCEPROP 2 LAST CDS_SEC 1
J 0
(-4275 3325);
DISPLAY 1.021277 (-4275 3325);
DISPLAY INVISIBLE (-4275 3325);
FORCEADD Q_CAPP..1
(-3750 3125);
FORCEPROP 1 LAST PART_NUMBER CC7560JMD16
J 0
(-3700 2925);
DISPLAY 0.617021 (-3700 2925);
PAINT BLUE (-3700 2925);
DISPLAY INVISIBLE (-3700 2925);
FORCEPROP 1 LAST PACK_TYPE THLF
J 0
(-3700 2975);
DISPLAY 0.617021 (-3700 2975);
PAINT SKYBLUE (-3700 2975);
FORCEPROP 1 LAST VALUE 560UF
J 0
(-3700 3175);
DISPLAY 0.617021 (-3700 3175);
PAINT SKYBLUE (-3700 3175);
FORCEPROP 1 LAST TOLERANCE 20%
J 0
(-3700 3125);
DISPLAY 0.617021 (-3700 3125);
PAINT SKYBLUE (-3700 3125);
FORCEPROP 1 LAST MATERIAL OSCON
J 0
(-3700 3025);
DISPLAY 0.617021 (-3700 3025);
PAINT SKYBLUE (-3700 3025);
FORCEPROP 1 LAST VOLTAGE 2.5V
J 0
(-3700 3075);
DISPLAY 0.617021 (-3700 3075);
PAINT SKYBLUE (-3700 3075);
FORCEPROP 1 LAST LOCATION PC1576
J 0
(-3700 3225);
DISPLAY 0.617021 (-3700 3225);
PAINT AQUA (-3700 3225);
FORCEPROP 1 LASTPIN (-3750 3225) $PN 1
J 0
(-3740 3210);
DISPLAY 0.617021 (-3740 3210);
PAINT MONO (-3740 3210);
FORCEPROP 1 LASTPIN (-3750 3025) $PN 2
J 0
(-3740 3010);
DISPLAY 0.617021 (-3740 3010);
PAINT MONO (-3740 3010);
FORCEPROP 2 LAST CDS_LIB pure_quanta
J 0
(-3750 3125);
DISPLAY INVISIBLE (-3750 3125);
FORCEPROP 1 LAST PATH I67
J 0
(-3700 3275);
DISPLAY 0.978723 (-3700 3275);
DISPLAY INVISIBLE (-3700 3275);
FORCEPROP 2 LAST $SEC 1
J 0
(-3700 3325);
DISPLAY 0.680851 (-3700 3325);
PAINT MONO (-3700 3325);
DISPLAY INVISIBLE (-3700 3325);
FORCEPROP 2 LAST CDS_SEC 1
J 0
(-3700 3325);
DISPLAY 1.021277 (-3700 3325);
DISPLAY INVISIBLE (-3700 3325);
FORCEADD Q_CAPP..1
(-4325 4050);
FORCEPROP 1 LAST PART_NUMBER CH733RY8807
J 0
(-4275 3850);
DISPLAY 0.617021 (-4275 3850);
PAINT BLUE (-4275 3850);
DISPLAY INVISIBLE (-4275 3850);
FORCEPROP 1 LAST MATERIAL SPCAP
J 0
(-4275 3950);
DISPLAY 0.617021 (-4275 3950);
PAINT SKYBLUE (-4275 3950);
FORCEPROP 1 LAST TOLERANCE 35%
J 0
(-4275 4050);
DISPLAY 0.617021 (-4275 4050);
PAINT SKYBLUE (-4275 4050);
FORCEPROP 1 LAST VALUE 330UF
J 0
(-4275 4100);
DISPLAY 0.617021 (-4275 4100);
PAINT SKYBLUE (-4275 4100);
FORCEPROP 1 LAST VOLTAGE 2V
J 0
(-4275 4000);
DISPLAY 0.617021 (-4275 4000);
PAINT SKYBLUE (-4275 4000);
FORCEPROP 1 LAST PACK_TYPE SMLF
J 0
(-4275 3900);
DISPLAY 0.617021 (-4275 3900);
PAINT SKYBLUE (-4275 3900);
FORCEPROP 1 LAST LOCATION PC1573
J 0
(-4275 4150);
DISPLAY 0.617021 (-4275 4150);
PAINT AQUA (-4275 4150);
FORCEPROP 1 LASTPIN (-4325 4150) $PN 1
J 0
(-4315 4135);
DISPLAY 0.617021 (-4315 4135);
PAINT MONO (-4315 4135);
FORCEPROP 1 LASTPIN (-4325 3950) $PN 2
J 0
(-4315 3935);
DISPLAY 0.617021 (-4315 3935);
PAINT MONO (-4315 3935);
FORCEPROP 2 LAST CDS_LIB pure_quanta
J 0
(-4325 4050);
DISPLAY INVISIBLE (-4325 4050);
FORCEPROP 1 LAST PATH I68
J 0
(-4275 4200);
DISPLAY 0.978723 (-4275 4200);
DISPLAY INVISIBLE (-4275 4200);
FORCEPROP 2 LAST $SEC 1
J 0
(-4275 4250);
DISPLAY 0.680851 (-4275 4250);
PAINT MONO (-4275 4250);
DISPLAY INVISIBLE (-4275 4250);
FORCEPROP 2 LAST CDS_SEC 1
J 0
(-4275 4250);
DISPLAY 1.021277 (-4275 4250);
DISPLAY INVISIBLE (-4275 4250);
FORCEADD Q_CAPP..1
(-3750 4050);
FORCEPROP 1 LAST PART_NUMBER CH733RY8807
J 0
(-3700 3850);
DISPLAY 0.617021 (-3700 3850);
PAINT BLUE (-3700 3850);
DISPLAY INVISIBLE (-3700 3850);
FORCEPROP 1 LAST MATERIAL SPCAP
J 0
(-3700 3950);
DISPLAY 0.617021 (-3700 3950);
PAINT SKYBLUE (-3700 3950);
FORCEPROP 1 LAST TOLERANCE 35%
J 0
(-3700 4050);
DISPLAY 0.617021 (-3700 4050);
PAINT SKYBLUE (-3700 4050);
FORCEPROP 1 LAST VALUE 330UF
J 0
(-3700 4100);
DISPLAY 0.617021 (-3700 4100);
PAINT SKYBLUE (-3700 4100);
FORCEPROP 1 LAST VOLTAGE 2V
J 0
(-3700 4000);
DISPLAY 0.617021 (-3700 4000);
PAINT SKYBLUE (-3700 4000);
FORCEPROP 1 LAST PACK_TYPE SMLF
J 0
(-3700 3900);
DISPLAY 0.617021 (-3700 3900);
PAINT SKYBLUE (-3700 3900);
FORCEPROP 1 LAST LOCATION PC1575
J 0
(-3700 4150);
DISPLAY 0.617021 (-3700 4150);
PAINT AQUA (-3700 4150);
FORCEPROP 1 LASTPIN (-3750 4150) $PN 1
J 0
(-3740 4135);
DISPLAY 0.617021 (-3740 4135);
PAINT MONO (-3740 4135);
FORCEPROP 1 LASTPIN (-3750 3950) $PN 2
J 0
(-3740 3935);
DISPLAY 0.617021 (-3740 3935);
PAINT MONO (-3740 3935);
FORCEPROP 2 LAST CDS_LIB pure_quanta
J 0
(-3750 4050);
DISPLAY INVISIBLE (-3750 4050);
FORCEPROP 1 LAST PATH I69
J 0
(-3700 4200);
DISPLAY 0.978723 (-3700 4200);
DISPLAY INVISIBLE (-3700 4200);
FORCEPROP 2 LAST $SEC 1
J 0
(-3700 4250);
DISPLAY 0.680851 (-3700 4250);
PAINT MONO (-3700 4250);
DISPLAY INVISIBLE (-3700 4250);
FORCEPROP 2 LAST CDS_SEC 1
J 0
(-3700 4250);
DISPLAY 1.021277 (-3700 4250);
DISPLAY INVISIBLE (-3700 4250);
FORCEADD OFFPAGE..5
(-10325 1475);
FORCEPROP 2 LAST $XR1 274 
J 0
(-10700 1475);
DISPLAY 0.638298 (-10700 1475);
PAINT MONO (-10700 1475);
FORCEPROP 2 LAST $XR0 275 
J 0
(-10580 1475);
DISPLAY 0.638298 (-10580 1475);
PAINT MONO (-10580 1475);
FORCEPROP 2 LAST CDS_LIB standard
J 0
(-10325 1475);
DISPLAY INVISIBLE (-10325 1475);
FORCEPROP 1 LAST OFFPAGE TRUE
J 0
(-10000 1350);
DISPLAY 0.872340 (-10000 1350);
PAINT GREEN (-10000 1350);
DISPLAY INVISIBLE (-10000 1350);
FORCEPROP 1 LAST COMMENT_BODY TRUE
J 0
(-10225 1400);
DISPLAY 0.872340 (-10225 1400);
PAINT GREEN (-10225 1400);
DISPLAY INVISIBLE (-10225 1400);
FORCEPROP 2 LAST PATH I7
J 0
(-10575 1525);
DISPLAY 1.021277 (-10575 1525);
DISPLAY INVISIBLE (-10575 1525);
FORCEADD Q_CAPP..1
(-3175 3125);
FORCEPROP 1 LAST PART_NUMBER CC7560JMD16
J 0
(-3125 2925);
DISPLAY 0.617021 (-3125 2925);
PAINT BLUE (-3125 2925);
DISPLAY INVISIBLE (-3125 2925);
FORCEPROP 1 LAST PACK_TYPE THLF
J 0
(-3125 2975);
DISPLAY 0.617021 (-3125 2975);
PAINT SKYBLUE (-3125 2975);
FORCEPROP 1 LAST VALUE 560UF
J 0
(-3125 3175);
DISPLAY 0.617021 (-3125 3175);
PAINT SKYBLUE (-3125 3175);
FORCEPROP 1 LAST TOLERANCE 20%
J 0
(-3125 3125);
DISPLAY 0.617021 (-3125 3125);
PAINT SKYBLUE (-3125 3125);
FORCEPROP 1 LAST MATERIAL OSCON
J 0
(-3125 3025);
DISPLAY 0.617021 (-3125 3025);
PAINT SKYBLUE (-3125 3025);
FORCEPROP 1 LAST VOLTAGE 2.5V
J 0
(-3125 3075);
DISPLAY 0.617021 (-3125 3075);
PAINT SKYBLUE (-3125 3075);
FORCEPROP 1 LAST LOCATION PC1579
J 0
(-3125 3225);
DISPLAY 0.617021 (-3125 3225);
PAINT AQUA (-3125 3225);
FORCEPROP 1 LASTPIN (-3175 3225) $PN 1
J 0
(-3165 3210);
DISPLAY 0.617021 (-3165 3210);
PAINT MONO (-3165 3210);
FORCEPROP 1 LASTPIN (-3175 3025) $PN 2
J 0
(-3165 3010);
DISPLAY 0.617021 (-3165 3010);
PAINT MONO (-3165 3010);
FORCEPROP 2 LAST CDS_LIB pure_quanta
J 0
(-3175 3125);
DISPLAY INVISIBLE (-3175 3125);
FORCEPROP 1 LAST PATH I70
J 0
(-3125 3275);
DISPLAY 0.978723 (-3125 3275);
DISPLAY INVISIBLE (-3125 3275);
FORCEPROP 2 LAST $SEC 1
J 0
(-3125 3325);
DISPLAY 0.680851 (-3125 3325);
PAINT MONO (-3125 3325);
DISPLAY INVISIBLE (-3125 3325);
FORCEPROP 2 LAST CDS_SEC 1
J 0
(-3125 3325);
DISPLAY 1.021277 (-3125 3325);
DISPLAY INVISIBLE (-3125 3325);
FORCEADD UNIVERSAL_GND..1
(-2575 2800);
FORCEPROP 3 LASTPIN (-2575 2850) SIG_NAME GND\g
J 0
(-2565 2860);
DISPLAY 0.659574 (-2565 2860);
PAINT MONO (-2565 2860);
DISPLAY INVISIBLE (-2565 2860);
FORCEPROP 2 LAST CDS_LIB logical_power
J 0
(-2575 2800);
PAINT MONO (-2575 2800);
DISPLAY INVISIBLE (-2575 2800);
FORCEPROP 1 LAST HDL_POWER GND
J 1
(-2550 2725);
DISPLAY 0.872340 (-2550 2725);
PAINT GREEN (-2550 2725);
DISPLAY INVISIBLE (-2550 2725);
FORCEPROP 1 LAST PATH I71
J 0
(-2500 2800);
DISPLAY 0.872340 (-2500 2800);
PAINT AQUA (-2500 2800);
DISPLAY INVISIBLE (-2500 2800);
FORCEPROP 2 LAST ROOM VR_CORE0_CTRL
J 0
(-2847 2922);
DISPLAY INVISIBLE (-2847 2922);
FORCEADD VCC15..1
(-2575 3450);
FORCEPROP 3 LASTPIN (-2575 3400) SIG_NAME PVCCINFAON_CPU0\g
J 0
(-2565 3410);
DISPLAY 0.659574 (-2565 3410);
PAINT MONO (-2565 3410);
DISPLAY INVISIBLE (-2565 3410);
FORCEPROP 1 LAST HDL_POWER PVCCINFAON_CPU0
J 1
(-2575 3500);
DISPLAY 0.617021 (-2575 3500);
PAINT GREEN (-2575 3500);
FORCEPROP 2 LAST CDS_LIB logical_power
J 0
(-2575 3450);
DISPLAY INVISIBLE (-2575 3450);
FORCEPROP 1 LAST PATH I72
J 0
(-2525 3475);
DISPLAY 0.872340 (-2525 3475);
PAINT AQUA (-2525 3475);
DISPLAY INVISIBLE (-2525 3475);
FORCEADD UNIVERSAL_GND..1
(-2575 3725);
FORCEPROP 3 LASTPIN (-2575 3775) SIG_NAME GND\g
J 0
(-2565 3785);
DISPLAY 0.659574 (-2565 3785);
PAINT MONO (-2565 3785);
DISPLAY INVISIBLE (-2565 3785);
FORCEPROP 2 LAST CDS_LIB logical_power
J 0
(-2575 3725);
PAINT MONO (-2575 3725);
DISPLAY INVISIBLE (-2575 3725);
FORCEPROP 1 LAST HDL_POWER GND
J 1
(-2550 3650);
DISPLAY 0.872340 (-2550 3650);
PAINT GREEN (-2550 3650);
DISPLAY INVISIBLE (-2550 3650);
FORCEPROP 1 LAST PATH I73
J 0
(-2500 3725);
DISPLAY 0.872340 (-2500 3725);
PAINT AQUA (-2500 3725);
DISPLAY INVISIBLE (-2500 3725);
FORCEPROP 2 LAST ROOM VR_CORE0_CTRL
J 0
(-2847 3847);
DISPLAY INVISIBLE (-2847 3847);
FORCEADD Q_CAPP..1
(-4275 5900);
FORCEPROP 1 LAST PART_NUMBER CC72703MD38
J 0
(-4225 5725);
DISPLAY 0.617021 (-4225 5725);
PAINT BLUE (-4225 5725);
DISPLAY INVISIBLE (-4225 5725);
FORCEPROP 1 LAST PACK_TYPE THLF
J 0
(-4225 5775);
DISPLAY 0.617021 (-4225 5775);
PAINT SKYBLUE (-4225 5775);
FORCEPROP 1 LAST TOLERANCE 20%
J 0
(-4225 5925);
DISPLAY 0.617021 (-4225 5925);
PAINT SKYBLUE (-4225 5925);
FORCEPROP 1 LAST MATERIAL OSCON
J 0
(-4225 5825);
DISPLAY 0.617021 (-4225 5825);
PAINT SKYBLUE (-4225 5825);
FORCEPROP 1 LAST VOLTAGE 16V
J 0
(-4225 5875);
DISPLAY 0.617021 (-4225 5875);
PAINT SKYBLUE (-4225 5875);
FORCEPROP 1 LAST VALUE 270UF
J 0
(-4225 5975);
DISPLAY 0.617021 (-4225 5975);
PAINT SKYBLUE (-4225 5975);
FORCEPROP 1 LAST LOCATION PC207
J 0
(-4225 6025);
DISPLAY 0.617021 (-4225 6025);
PAINT AQUA (-4225 6025);
FORCEPROP 1 LASTPIN (-4275 6000) $PN 1
J 0
(-4265 5985);
DISPLAY 0.617021 (-4265 5985);
PAINT MONO (-4265 5985);
FORCEPROP 1 LASTPIN (-4275 5800) $PN 2
J 0
(-4265 5785);
DISPLAY 0.617021 (-4265 5785);
PAINT MONO (-4265 5785);
FORCEPROP 2 LAST CDS_LIB pure_quanta
J 0
(-4275 5900);
DISPLAY INVISIBLE (-4275 5900);
FORCEPROP 1 LAST PATH I74
J 0
(-4225 6050);
DISPLAY 0.978723 (-4225 6050);
DISPLAY INVISIBLE (-4225 6050);
FORCEPROP 1 LAST LOCATION PC207
J 0
(-4225 6075);
DISPLAY 1.021277 (-4225 6075);
PAINT AQUA (-4225 6075);
DISPLAY INVISIBLE (-4225 6075);
FORCEPROP 0 LAST $SEC 1
J 0
(-4225 6075);
DISPLAY 0.680851 (-4225 6075);
PAINT MONO (-4225 6075);
DISPLAY INVISIBLE (-4225 6075);
FORCEPROP 0 LAST CDS_SEC 1
J 0
(-4225 6075);
DISPLAY 1.021277 (-4225 6075);
DISPLAY INVISIBLE (-4225 6075);
FORCEADD Q_CAPP..1
(-3875 5900);
FORCEPROP 1 LAST PART_NUMBER CC72703MD38
J 0
(-3825 5725);
DISPLAY 0.617021 (-3825 5725);
PAINT BLUE (-3825 5725);
DISPLAY INVISIBLE (-3825 5725);
FORCEPROP 1 LAST PACK_TYPE THLF
J 0
(-3825 5775);
DISPLAY 0.617021 (-3825 5775);
PAINT SKYBLUE (-3825 5775);
FORCEPROP 1 LAST TOLERANCE 20%
J 0
(-3825 5925);
DISPLAY 0.617021 (-3825 5925);
PAINT SKYBLUE (-3825 5925);
FORCEPROP 1 LAST MATERIAL OSCON
J 0
(-3825 5825);
DISPLAY 0.617021 (-3825 5825);
PAINT SKYBLUE (-3825 5825);
FORCEPROP 1 LAST VOLTAGE 16V
J 0
(-3825 5875);
DISPLAY 0.617021 (-3825 5875);
PAINT SKYBLUE (-3825 5875);
FORCEPROP 1 LAST VALUE 270UF
J 0
(-3825 5975);
DISPLAY 0.617021 (-3825 5975);
PAINT SKYBLUE (-3825 5975);
FORCEPROP 1 LAST LOCATION PC208
J 0
(-3825 6025);
DISPLAY 0.617021 (-3825 6025);
PAINT AQUA (-3825 6025);
FORCEPROP 1 LASTPIN (-3875 6000) $PN 1
J 0
(-3865 5985);
DISPLAY 0.617021 (-3865 5985);
PAINT MONO (-3865 5985);
FORCEPROP 1 LASTPIN (-3875 5800) $PN 2
J 0
(-3865 5785);
DISPLAY 0.617021 (-3865 5785);
PAINT MONO (-3865 5785);
FORCEPROP 2 LAST CDS_LIB pure_quanta
J 0
(-3875 5900);
DISPLAY INVISIBLE (-3875 5900);
FORCEPROP 1 LAST PATH I75
J 0
(-3825 6050);
DISPLAY 0.978723 (-3825 6050);
DISPLAY INVISIBLE (-3825 6050);
FORCEPROP 1 LAST LOCATION PC208
J 0
(-3825 6075);
DISPLAY 1.021277 (-3825 6075);
PAINT AQUA (-3825 6075);
DISPLAY INVISIBLE (-3825 6075);
FORCEPROP 0 LAST $SEC 1
J 0
(-3825 6075);
DISPLAY 0.680851 (-3825 6075);
PAINT MONO (-3825 6075);
DISPLAY INVISIBLE (-3825 6075);
FORCEPROP 0 LAST CDS_SEC 1
J 0
(-3825 6075);
DISPLAY 1.021277 (-3825 6075);
DISPLAY INVISIBLE (-3825 6075);
FORCEADD UNIVERSAL_GND..1
(-2675 5575);
FORCEPROP 3 LASTPIN (-2675 5625) SIG_NAME GND\g
J 0
(-2665 5635);
DISPLAY 0.659574 (-2665 5635);
PAINT MONO (-2665 5635);
DISPLAY INVISIBLE (-2665 5635);
FORCEPROP 2 LAST CDS_LIB logical_power
J 0
(-2675 5575);
PAINT MONO (-2675 5575);
DISPLAY INVISIBLE (-2675 5575);
FORCEPROP 1 LAST HDL_POWER GND
J 1
(-2650 5500);
DISPLAY 0.872340 (-2650 5500);
PAINT GREEN (-2650 5500);
DISPLAY INVISIBLE (-2650 5500);
FORCEPROP 1 LAST PATH I76
J 0
(-2600 5575);
DISPLAY 0.872340 (-2600 5575);
PAINT AQUA (-2600 5575);
DISPLAY INVISIBLE (-2600 5575);
FORCEPROP 2 LAST ROOM VR_CORE0_CTRL
J 0
(-2947 5697);
DISPLAY INVISIBLE (-2947 5697);
FORCEADD VCC15..1
(-2675 6225);
FORCEPROP 3 LASTPIN (-2675 6175) SIG_NAME SW_P12V_PVCCINFAON_CPU0_FLT\g
J 0
(-2665 6185);
DISPLAY 0.659574 (-2665 6185);
PAINT MONO (-2665 6185);
DISPLAY INVISIBLE (-2665 6185);
FORCEPROP 1 LAST HDL_POWER SW_P12V_PVCCINFAON_CPU0_FLT
J 1
(-2625 6275);
DISPLAY 0.617021 (-2625 6275);
PAINT GREEN (-2625 6275);
FORCEPROP 2 LAST CDS_LIB logical_power
J 0
(-2675 6225);
DISPLAY INVISIBLE (-2675 6225);
FORCEPROP 1 LAST PATH I77
J 0
(-2625 6250);
DISPLAY 0.872340 (-2625 6250);
PAINT AQUA (-2625 6250);
DISPLAY INVISIBLE (-2625 6250);
FORCEADD VCC15..1
(-2575 4375);
FORCEPROP 3 LASTPIN (-2575 4325) SIG_NAME PVCCINFAON_CPU0\g
J 0
(-2565 4335);
DISPLAY 0.659574 (-2565 4335);
PAINT MONO (-2565 4335);
DISPLAY INVISIBLE (-2565 4335);
FORCEPROP 1 LAST HDL_POWER PVCCINFAON_CPU0
J 1
(-2575 4425);
DISPLAY 0.617021 (-2575 4425);
PAINT GREEN (-2575 4425);
FORCEPROP 2 LAST CDS_LIB logical_power
J 0
(-2575 4375);
DISPLAY INVISIBLE (-2575 4375);
FORCEPROP 1 LAST PATH I78
J 0
(-2525 4400);
DISPLAY 0.872340 (-2525 4400);
PAINT AQUA (-2525 4400);
DISPLAY INVISIBLE (-2525 4400);
FORCEADD ISL99390FRZTR5935..1
(-8725 4775);
FORCEPROP 1 LAST PART_NUMBER AL099390004
J 0
(-9025 5575);
DISPLAY 0.723404 (-9025 5575);
PAINT GREEN (-9025 5575);
DISPLAY INVISIBLE (-9025 5575);
FORCEPROP 1 LAST MATERIAL IC
J 0
(-9025 5500);
DISPLAY 0.723404 (-9025 5500);
PAINT GREEN (-9025 5500);
FORCEPROP 2 LAST PART_TYPE SMLF
J 0
(-9000 5875);
DISPLAY 1.595745 (-9000 5875);
FORCEPROP 2 LAST VALUE ISL99390FRZ-TR5935
J 0
(-9000 5775);
DISPLAY 0.957447 (-9000 5775);
PAINT SKYBLUE (-9000 5775);
FORCEPROP 1 LAST LOCATION PU43_P0_1
J 0
(-9025 5650);
DISPLAY 0.723404 (-9025 5650);
PAINT GREEN (-9025 5650);
FORCEPROP 2 LASTPIN (-8325 4325) $PN 2
J 0
(-8315 4335);
DISPLAY 0.680851 (-8315 4335);
PAINT MONO (-8315 4335);
FORCEPROP 2 LASTPIN (-8325 5125) $PN 33
J 0
(-8315 5135);
DISPLAY 0.680851 (-8315 5135);
PAINT MONO (-8315 5135);
FORCEPROP 2 LASTPIN (-9175 4525) $PN 31
J 2
(-9185 4535);
DISPLAY 0.680851 (-9185 4535);
PAINT MONO (-9185 4535);
FORCEPROP 2 LASTPIN (-9175 4925) $PN 35
J 2
(-9185 4935);
DISPLAY 0.680851 (-9185 4935);
PAINT MONO (-9185 4935);
FORCEPROP 2 LASTPIN (-8325 4475) $PN 6
J 0
(-8315 4485);
DISPLAY 0.680851 (-8315 4485);
PAINT MONO (-8315 4485);
FORCEPROP 2 LASTPIN (-8325 4425) $PN 41
J 0
(-8315 4435);
DISPLAY 0.680851 (-8315 4435);
PAINT MONO (-8315 4435);
FORCEPROP 2 LASTPIN (-9175 4775) $PN 38
J 2
(-9185 4785);
DISPLAY 0.680851 (-9185 4785);
PAINT MONO (-9185 4785);
FORCEPROP 2 LASTPIN (-9175 4475) $PN 37
J 2
(-9185 4485);
DISPLAY 0.680851 (-9185 4485);
PAINT MONO (-9185 4485);
FORCEPROP 2 LASTPIN (-8325 4275) $PN 5
J 0
(-8315 4285);
DISPLAY 0.680851 (-8315 4285);
PAINT MONO (-8315 4285);
FORCEPROP 2 LASTPIN (-8325 4225) $PN 7_9-20_24
J 0
(-8315 4235);
DISPLAY 0.680851 (-8315 4235);
PAINT MONO (-8315 4235);
FORCEPROP 2 LASTPIN (-8325 4175) $PN 40
J 0
(-8315 4185);
DISPLAY 0.680851 (-8315 4185);
PAINT MONO (-8315 4185);
FORCEPROP 2 LASTPIN (-8325 4875) $PN 32
J 0
(-8315 4885);
DISPLAY 0.680851 (-8315 4885);
PAINT MONO (-8315 4885);
FORCEPROP 2 LASTPIN (-9175 5425) $PN 4
J 2
(-9185 5435);
DISPLAY 0.680851 (-9185 5435);
PAINT MONO (-9185 5435);
FORCEPROP 2 LASTPIN (-9175 4175) $PN 34
J 2
(-9185 4185);
DISPLAY 0.680851 (-9185 4185);
PAINT MONO (-9185 4185);
FORCEPROP 2 LASTPIN (-9175 4675) $PN 39
J 2
(-9185 4685);
DISPLAY 0.680851 (-9185 4685);
PAINT MONO (-9185 4685);
FORCEPROP 2 LASTPIN (-8325 4775) $PN 10_19
J 0
(-8315 4785);
DISPLAY 0.680851 (-8315 4785);
PAINT MONO (-8315 4785);
FORCEPROP 2 LASTPIN (-9175 4275) $PN 36
J 2
(-9185 4285);
DISPLAY 0.680851 (-9185 4285);
PAINT MONO (-9185 4285);
FORCEPROP 2 LASTPIN (-9175 5125) $PN 3
J 2
(-9185 5135);
DISPLAY 0.680851 (-9185 5135);
PAINT MONO (-9185 5135);
FORCEPROP 2 LASTPIN (-8325 5425) $PN 25_29
J 0
(-8315 5435);
DISPLAY 0.680851 (-8315 5435);
PAINT MONO (-8315 5435);
FORCEPROP 2 LASTPIN (-8325 5375) $PN 30
J 0
(-8315 5385);
DISPLAY 0.680851 (-8315 5385);
PAINT MONO (-8315 5385);
FORCEPROP 2 LASTPIN (-8325 4525) $PN 1
J 0
(-8315 4535);
DISPLAY 0.680851 (-8315 4535);
PAINT MONO (-8315 4535);
FORCEPROP 2 LAST CDS_LIB pure_quanta
J 0
(-8725 4775);
DISPLAY INVISIBLE (-8725 4775);
FORCEPROP 1 LAST CDS_LMAN_SYM_OUTLINE -300,700,250,-650
J 0
(-8725 4775);
DISPLAY 0.468085 (-8725 4775);
PAINT GREEN (-8725 4775);
DISPLAY INVISIBLE (-8725 4775);
FORCEPROP 1 LAST NEEDS_NO_SIZE TRUE
J 0
(-8725 4775);
DISPLAY 0.723404 (-8725 4775);
PAINT GREEN (-8725 4775);
DISPLAY INVISIBLE (-8725 4775);
FORCEPROP 2 LAST SEC_TYPE 
J 0
(-9000 5950);
DISPLAY 1.021277 (-9000 5950);
DISPLAY INVISIBLE (-9000 5950);
FORCEPROP 1 LAST PATH I79
J 0
(-8725 4775);
DISPLAY 0.723404 (-8725 4775);
PAINT GREEN (-8725 4775);
DISPLAY INVISIBLE (-8725 4775);
FORCEPROP 2 LAST SEC 1
J 0
(-9000 5950);
DISPLAY 0.680851 (-9000 5950);
PAINT MONO (-9000 5950);
DISPLAY INVISIBLE (-9000 5950);
FORCEADD OFFPAGE..1
(-10325 1875);
FORCEPROP 2 LAST $XR2 276 
J 0
(-10817 1875);
DISPLAY 0.638298 (-10817 1875);
PAINT MONO (-10817 1875);
FORCEPROP 2 LAST $XR1 275 
J 0
(-10697 1875);
DISPLAY 0.638298 (-10697 1875);
PAINT MONO (-10697 1875);
FORCEPROP 2 LAST $XR0 274 
J 0
(-10577 1875);
DISPLAY 0.638298 (-10577 1875);
PAINT MONO (-10577 1875);
FORCEPROP 2 LAST CDS_LIB standard
J 0
(-10325 1875);
DISPLAY INVISIBLE (-10325 1875);
FORCEPROP 1 LAST OFFPAGE TRUE
J 0
(-10000 1750);
DISPLAY 0.872340 (-10000 1750);
PAINT GREEN (-10000 1750);
DISPLAY INVISIBLE (-10000 1750);
FORCEPROP 1 LAST COMMENT_BODY TRUE
J 0
(-10200 1775);
DISPLAY 0.872340 (-10200 1775);
PAINT GREEN (-10200 1775);
DISPLAY INVISIBLE (-10200 1775);
FORCEPROP 2 LAST PATH I8
J 0
(-10575 1925);
DISPLAY 1.021277 (-10575 1925);
DISPLAY INVISIBLE (-10575 1925);
FORCEADD OFFPAGE..5
(-10325 1975);
FORCEPROP 2 LAST $XR0 274 
J 0
(-10580 1975);
DISPLAY 0.638298 (-10580 1975);
PAINT MONO (-10580 1975);
FORCEPROP 2 LAST CDS_LIB standard
J 0
(-10325 1975);
DISPLAY INVISIBLE (-10325 1975);
FORCEPROP 1 LAST OFFPAGE TRUE
J 0
(-10000 1850);
DISPLAY 0.872340 (-10000 1850);
PAINT GREEN (-10000 1850);
DISPLAY INVISIBLE (-10000 1850);
FORCEPROP 1 LAST COMMENT_BODY TRUE
J 0
(-10225 1900);
DISPLAY 0.872340 (-10225 1900);
PAINT GREEN (-10225 1900);
DISPLAY INVISIBLE (-10225 1900);
FORCEPROP 2 LAST PATH I9
J 0
(-10575 2025);
DISPLAY 1.021277 (-10575 2025);
DISPLAY INVISIBLE (-10575 2025);
FORCEADD DNS..1
(-10900 1375);
PAINT RED (-10900 1375);
FORCEPROP 2 LAST CDS_LIB mstr_misc
J 0
(-10900 1375);
DISPLAY INVISIBLE (-10900 1375);
FORCEPROP 1 LAST COMMENT_BODY TRUE
R 1
J 0
(-10825 1150);
DISPLAY 0.872340 (-10825 1150);
PAINT GREEN (-10825 1150);
DISPLAY INVISIBLE (-10825 1150);
FORCEADD DNS..1
(-10875 4175);
PAINT RED (-10875 4175);
FORCEPROP 2 LAST CDS_LIB mstr_misc
J 0
(-10875 4175);
DISPLAY INVISIBLE (-10875 4175);
FORCEPROP 1 LAST COMMENT_BODY TRUE
R 1
J 0
(-10800 3950);
DISPLAY 0.872340 (-10800 3950);
PAINT GREEN (-10800 3950);
DISPLAY INVISIBLE (-10800 3950);
FORCEADD QUANTA_TITLE_BLOCK_C..1
(-2000 425);
FORCEPROP 0 LAST CDS_CON_LAST_MODIFIED Fri Aug 25 14:04:46 2023
J 0
(-3885 440);
DISPLAY INVISIBLE (-3885 440);
FORCEPROP 1 LAST CUSTOM_TXT_CDS <CON_LAST_MODIFIED>
J 0
(-3885 440);
DISPLAY 0.978723 (-3885 440);
FORCEPROP 2 LAST CUSTOM_TXT_CDS <XR_PAGE_TITLE>
J 0
(-9890 5675);
DISPLAY 0.638298 (-9890 5675);
PAINT PINK (-9890 5675);
DISPLAY INVISIBLE (-9890 5675);
FORCEPROP 1 LAST CUSTOM_TXT_CDS <NAME_2>
J 0
(-5175 475);
FORCEPROP 1 LAST CUSTOM_TXT_CDS <NAME_1>
J 0
(-5175 600);
FORCEPROP 1 LAST CUSTOM_TXT_CDS <Q_NUMBER>
J 0
(-3403 528);
DISPLAY 1.212766 (-3403 528);
FORCEPROP 1 LAST CUSTOM_TXT_CDS <Q_PROJ>
J 0
(-4382 527);
DISPLAY 1.212766 (-4382 527);
FORCEPROP 1 LAST CUSTOM_TXT_CDS <Q_REV>
J 0
(-2184 528);
DISPLAY 1.212766 (-2184 528);
FORCEPROP 1 LAST CUSTOM_TXT_CDS <CON_PAGE_NUM> OF <CON_TOTAL_PAGES>
J 0
(-2446 443);
DISPLAY 0.978723 (-2446 443);
FORCEPROP 1 LAST Q_TITLE VCCINFAON CPU0 VR PHASE 1&2 (2/3)
J 0
(-11300 475);
DISPLAY 2.446809 (-11300 475);
PAINT GREEN (-11300 475);
FORCEPROP 1 LAST Q_DEPT 
J 1
(-5763 474);
DISPLAY 1.957447 (-5763 474);
PAINT GREEN (-5763 474);
FORCEPROP 2 LAST CDS_XR_PAGE_TITLE CR-275 : @S9S_MB_2U_LIB.S9S_MB_2U(SCH_1):PAGE275
J 0
(-9890 5675);
DISPLAY 0.638298 (-9890 5675);
PAINT PINK (-9890 5675);
DISPLAY INVISIBLE (-9890 5675);
FORCEPROP 1 LAST COMMENT_BODY TRUE
J 0
(-1988 412);
DISPLAY 0.978723 (-1988 412);
PAINT GREEN (-1988 412);
DISPLAY INVISIBLE (-1988 412);
FORCEPROP 2 LAST PAGE_BORDER TRUE
J 0
(-9890 5675);
DISPLAY 0.638298 (-9890 5675);
PAINT PINK (-9890 5675);
DISPLAY INVISIBLE (-9890 5675);
FORCEPROP 1 LAST CDS_LMAN_SYM_OUTLINE -9475,6775,100,-125
J 0
(-2000 425);
DISPLAY 0.468085 (-2000 425);
PAINT GREEN (-2000 425);
DISPLAY INVISIBLE (-2000 425);
FORCEPROP 2 LAST CDS_LIB pure_quanta
J 0
(-2000 425);
DISPLAY INVISIBLE (-2000 425);
WIRE 16 -1 (-10400 3175)(-10400 3300);
WIRE 16 -1 (-9875 3175)(-10400 3175);
FORCEPROP 0 LAST SIG_NAME PVCCFA_EHV_CPU0_PVCC
J 0
(-10360 3210);
DISPLAY 0.659574 (-10360 3210);
FORCEPROP 2 LASTPROP $XR2 279 
J 0
(-10756 3210);
DISPLAY 0.638298 (-10756 3210);
PAINT MONO (-10756 3210);
FORCEPROP 2 LASTPROP $XR1 276 
J 0
(-10636 3210);
DISPLAY 0.638298 (-10636 3210);
PAINT MONO (-10636 3210);
FORCEPROP 2 LASTPROP $XR0 275 
J 0
(-10516 3210);
DISPLAY 0.638298 (-10516 3210);
PAINT MONO (-10516 3210);
WIRE 16 -1 (-10400 5900)(-10400 6025);
FORCEPROP 2 LAST SIG_NAME PVCCFA_EHV_CPU0_PVCC
J 0
(-10360 5935);
DISPLAY 0.617021 (-10360 5935);
FORCEPROP 2 LASTPROP $XR2 279 
J 0
(-10756 5935);
DISPLAY 0.638298 (-10756 5935);
PAINT MONO (-10756 5935);
FORCEPROP 2 LASTPROP $XR1 276 
J 0
(-10636 5935);
DISPLAY 0.638298 (-10636 5935);
PAINT MONO (-10636 5935);
FORCEPROP 2 LASTPROP $XR0 275 
J 0
(-10516 5935);
DISPLAY 0.638298 (-10516 5935);
PAINT MONO (-10516 5935);
WIRE 16 -1 (-6275 3200)(-6275 3125);
WIRE 16 -1 (-6275 6000)(-6275 5925);
WIRE 16 -1 (-4975 4925)(-4975 4775);
WIRE 16 -1 (-5025 6225)(-5025 6100);
WIRE 16 -1 (-4250 2100)(-4250 1975);
WIRE 16 -1 (-2575 3400)(-2575 3350);
WIRE 16 -1 (-2675 6175)(-2675 6100);
WIRE 16 -1 (-2575 4325)(-2575 4275);
WIRE 16 -1 (-10900 1300)(-10900 1225);
WIRE 16 -1 (-11050 1800)(-11050 1750);
WIRE 16 -1 (-11050 1800)(-10325 1800);
WIRE 16 -1 (-10875 4100)(-10875 4025);
WIRE 16 -1 (-10400 2325)(-10400 2225);
WIRE 16 -1 (-9875 2800)(-9875 2725);
WIRE 16 -1 (-11025 4600)(-11025 4550);
WIRE 16 -1 (-11025 4600)(-10300 4600);
WIRE 16 -1 (-10400 5125)(-10400 5025);
WIRE 16 -1 (-9825 5550)(-9825 5450);
WIRE 16 -1 (-8225 1375)(-8225 1300);
WIRE 16 -1 (-8225 1425)(-8225 1375);
WIRE 16 -1 (-8475 1375)(-8225 1375);
WIRE 16 -1 (-8225 4175)(-8225 4100);
WIRE 16 -1 (-8225 4225)(-8225 4175);
WIRE 16 -1 (-8325 4175)(-8225 4175);
WIRE 16 -1 (-6275 2500)(-6275 2625);
WIRE 16 -1 (-4975 4250)(-4975 4350);
WIRE 16 -1 (-6275 5300)(-6275 5425);
WIRE 16 -1 (-5025 5700)(-5025 5800);
WIRE 16 -1 (-4250 1450)(-4250 1550);
WIRE 16 -1 (-2575 2900)(-2575 2850);
WIRE 16 -1 (-3175 2900)(-2575 2900);
WIRE 16 -1 (-2575 3825)(-2575 3775);
WIRE 16 -1 (-3750 3825)(-2575 3825);
WIRE 16 -1 (-2675 5625)(-2675 5700);
WIRE 16 -1 (-4275 5800)(-4275 5700);
WIRE 16 -1 (-4275 5700)(-3875 5700);
WIRE 16 -1 (-3875 5800)(-3875 5700);
WIRE 16 -1 (-2675 5700)(-3875 5700);
WIRE 16 -1 (-4275 6100)(-4500 6100);
WIRE 16 -1 (-4275 6100)(-4275 6000);
WIRE 16 -1 (-4275 6100)(-3875 6100);
WIRE 16 -1 (-3875 6000)(-3875 6100);
WIRE 16 -1 (-2675 6100)(-3875 6100);
WIRE 16 -1 (-3175 3025)(-3175 2900);
WIRE 16 -1 (-3750 2900)(-3750 3025);
WIRE 16 -1 (-3750 2900)(-3175 2900);
WIRE 16 -1 (-4325 2900)(-3750 2900);
WIRE 16 -1 (-4325 3025)(-4325 2900);
WIRE 16 -1 (-3175 3225)(-3175 3350);
WIRE 16 -1 (-2575 3350)(-3175 3350);
WIRE 16 -1 (-3750 3350)(-3750 3225);
WIRE 16 -1 (-3750 3350)(-3175 3350);
WIRE 16 -1 (-4325 3350)(-3750 3350);
WIRE 16 -1 (-4325 3225)(-4325 3350);
WIRE 16 -1 (-3750 4275)(-3750 4150);
WIRE 16 -1 (-3750 4275)(-2575 4275);
WIRE 16 -1 (-4325 4275)(-3750 4275);
WIRE 16 -1 (-4325 4150)(-4325 4275);
WIRE 16 -1 (-4325 3950)(-4325 3825);
WIRE 16 -1 (-4325 3825)(-3750 3825);
WIRE 16 -1 (-3750 3825)(-3750 3950);
WIRE 16 -1 (-4575 1975)(-4575 1875);
WIRE 16 -1 (-4250 1975)(-4575 1975);
WIRE 16 -1 (-5050 1875)(-5050 1975);
WIRE 16 -1 (-4575 1975)(-5050 1975);
WIRE 16 -1 (-5475 1975)(-5475 1875);
WIRE 16 -1 (-5475 1975)(-5050 1975);
WIRE 16 -1 (-6350 1975)(-5975 1975);
WIRE 16 -1 (-5975 1975)(-5475 1975);
WIRE 16 -1 (-5975 1725)(-5975 1975);
WIRE 16 -1 (-7200 1725)(-5975 1725);
WIRE 16 -1 (-5475 1550)(-5475 1675);
WIRE 16 -1 (-5050 1550)(-5475 1550);
WIRE 16 -1 (-5050 1675)(-5050 1550);
WIRE 16 -1 (-4575 1550)(-5050 1550);
WIRE 16 -1 (-4575 1675)(-4575 1550);
WIRE 16 -1 (-4250 1550)(-4575 1550);
WIRE 16 -1 (-5025 6100)(-4700 6100);
WIRE 16 -1 (-5025 6000)(-5025 6100);
WIRE 16 -1 (-5275 4675)(-5275 4775);
WIRE 16 -1 (-4975 4775)(-5275 4775);
WIRE 16 -1 (-5700 4775)(-5700 4675);
WIRE 16 -1 (-5700 4775)(-5275 4775);
WIRE 16 -1 (-6100 4675)(-6100 4775);
WIRE 16 -1 (-6100 4775)(-5700 4775);
WIRE 16 -1 (-6225 4775)(-6350 4775);
WIRE 16 -1 (-6100 4775)(-6225 4775);
WIRE 16 -1 (-6225 4775)(-6225 4525);
WIRE 16 -1 (-7225 4525)(-6225 4525);
WIRE 16 -1 (-5275 4475)(-5275 4350);
WIRE 16 -1 (-4975 4350)(-5275 4350);
WIRE 16 -1 (-5700 4350)(-5700 4475);
WIRE 16 -1 (-5275 4350)(-5700 4350);
WIRE 16 -1 (-6100 4350)(-5700 4350);
WIRE 16 -1 (-6100 4475)(-6100 4350);
WIRE 16 -1 (-6700 5225)(-6700 5150);
WIRE 16 -1 (-7425 5225)(-6700 5225);
FORCEPROP 2 LAST SIG_NAME SW_PVCCINFAON_CPU0_BOOT1_R
J 0
(-7210 5235);
DISPLAY 0.617021 (-7210 5235);
WIRE 16 -1 (-6700 4875)(-6700 4950);
WIRE 16 -1 (-8325 4875)(-6700 4875);
FORCEPROP 0 LAST CDS_PHYS_NET_NAME SW_PVCCINFAON_CPU0_BOOTR1
J 0
(-8135 4915);
PAINT MONO (-8135 4915);
DISPLAY INVISIBLE (-8135 4915);
FORCEPROP 2 LAST SIG_NAME SW_PVCCINFAON_CPU0_BOOTR1
J 0
(-8135 4885);
DISPLAY 0.617021 (-8135 4885);
WIRE 16 -1 (-8325 4775)(-6550 4775);
FORCEPROP 2 LAST SIG_NAME SW_PVCCINFAON_CPU0_SW1
J 0
(-8135 4785);
DISPLAY 0.617021 (-8135 4785);
WIRE 16 -1 (-6875 5775)(-6875 5925);
WIRE 16 -1 (-6275 5925)(-6875 5925);
WIRE 16 -1 (-7275 5925)(-7275 5775);
WIRE 16 -1 (-7275 5925)(-6875 5925);
WIRE 16 -1 (-7675 5775)(-7675 5925);
WIRE 16 -1 (-7675 5925)(-7275 5925);
WIRE 16 -1 (-8075 5775)(-8075 5925);
WIRE 16 -1 (-8075 5925)(-7675 5925);
WIRE 16 -1 (-8175 5925)(-8075 5925);
WIRE 16 -1 (-8325 5425)(-8175 5425);
WIRE 16 -1 (-8175 5925)(-8175 5425);
WIRE 16 -1 (-8175 5375)(-8175 5425);
WIRE 16 -1 (-8325 5375)(-8175 5375);
WIRE 16 -1 (-6875 5575)(-6875 5425);
WIRE 16 -1 (-6275 5425)(-6875 5425);
WIRE 16 -1 (-7275 5575)(-7275 5425);
WIRE 16 -1 (-7275 5425)(-6875 5425);
WIRE 16 -1 (-7675 5575)(-7675 5425);
WIRE 16 -1 (-7275 5425)(-7675 5425);
WIRE 16 -1 (-8075 5425)(-7675 5425);
WIRE 16 -1 (-8075 5575)(-8075 5425);
WIRE 16 -1 (-8325 4525)(-7425 4525);
FORCEPROP 2 LAST SIG_NAME PVCCINFAON_CPU0_VOS1
J 0
(-8235 4535);
DISPLAY 0.638298 (-8235 4535);
WIRE 16 -1 (-8225 4325)(-8325 4325);
WIRE 16 -1 (-8325 4275)(-8225 4275);
WIRE 16 -1 (-8225 4275)(-8225 4325);
WIRE 16 -1 (-8225 4225)(-8225 4275);
WIRE 16 -1 (-8325 4225)(-8225 4225);
WIRE 16 -1 (-8325 5225)(-7625 5225);
FORCEPROP 0 LAST CDS_PHYS_NET_NAME SW_PVCCINFAON_CPU0_BOOT1
J 0
(-8285 5254);
PAINT MONO (-8285 5254);
DISPLAY INVISIBLE (-8285 5254);
WIRE 16 -1 (-8325 5125)(-8325 5225);
FORCEPROP 2 LAST SIG_NAME SW_PVCCINFAON_CPU0_BOOT1
J 0
(-8485 5235);
DISPLAY 0.617021 (-8485 5235);
WIRE 16 -1 (-6875 2975)(-6875 3125);
WIRE 16 -1 (-6275 3125)(-6875 3125);
WIRE 16 -1 (-7275 3125)(-7275 2975);
WIRE 16 -1 (-7275 3125)(-6875 3125);
WIRE 16 -1 (-7675 2975)(-7675 3125);
WIRE 16 -1 (-7675 3125)(-7275 3125);
WIRE 16 -1 (-8075 2975)(-8075 3125);
WIRE 16 -1 (-8075 3125)(-7675 3125);
WIRE 16 -1 (-8275 3125)(-8075 3125);
WIRE 16 -1 (-8475 2625)(-8275 2625);
WIRE 16 -1 (-8275 3125)(-8275 2625);
WIRE 16 -1 (-8275 2575)(-8275 2625);
WIRE 16 -1 (-8475 2575)(-8275 2575);
WIRE 16 -1 (-8475 1975)(-6550 1975);
FORCEPROP 2 LAST SIG_NAME SW_PVCCINFAON_CPU0_SW2
J 0
(-8285 1985);
DISPLAY 0.617021 (-8285 1985);
WIRE 16 -1 (-6700 2425)(-6700 2350);
WIRE 16 -1 (-7425 2425)(-6700 2425);
FORCEPROP 2 LAST SIG_NAME SW_PVCCINFAON_CPU0_BOOT2_R
J 0
(-7210 2435);
DISPLAY 0.617021 (-7210 2435);
WIRE 16 -1 (-6875 2775)(-6875 2625);
WIRE 16 -1 (-6275 2625)(-6875 2625);
WIRE 16 -1 (-7275 2775)(-7275 2625);
WIRE 16 -1 (-7275 2625)(-6875 2625);
WIRE 16 -1 (-7675 2775)(-7675 2625);
WIRE 16 -1 (-7275 2625)(-7675 2625);
WIRE 16 -1 (-8075 2625)(-7675 2625);
WIRE 16 -1 (-8075 2775)(-8075 2625);
WIRE 16 -1 (-6700 2075)(-6700 2150);
WIRE 16 -1 (-8475 2075)(-6700 2075);
FORCEPROP 0 LAST CDS_PHYS_NET_NAME SW_PVCCINFAON_CPU0_BOOTR2
J 0
(-8285 2115);
PAINT MONO (-8285 2115);
DISPLAY INVISIBLE (-8285 2115);
FORCEPROP 2 LAST SIG_NAME SW_PVCCINFAON_CPU0_BOOTR2
J 0
(-8285 2085);
DISPLAY 0.617021 (-8285 2085);
WIRE 16 -1 (-8325 2425)(-7625 2425);
FORCEPROP 0 LAST CDS_PHYS_NET_NAME SW_PVCCINFAON_CPU0_BOOT2
J 0
(-8285 2454);
PAINT MONO (-8285 2454);
DISPLAY INVISIBLE (-8285 2454);
WIRE 16 -1 (-8325 2325)(-8325 2425);
FORCEPROP 2 LAST SIG_NAME SW_PVCCINFAON_CPU0_BOOT2
J 0
(-8485 2435);
DISPLAY 0.617021 (-8485 2435);
WIRE 16 -1 (-8475 2325)(-8325 2325);
WIRE 16 -1 (-7400 1725)(-8475 1725);
FORCEPROP 2 LAST SIG_NAME PVCCINFAON_CPU0_VOS2
J 0
(-8310 1760);
DISPLAY 0.638298 (-8310 1760);
WIRE 16 -1 (-8225 1525)(-8475 1525);
WIRE 16 -1 (-8475 1475)(-8225 1475);
WIRE 16 -1 (-8225 1475)(-8225 1525);
WIRE 16 -1 (-8225 1425)(-8225 1475);
WIRE 16 -1 (-8475 1425)(-8225 1425);
WIRE 16 -1 (-9175 5425)(-9375 5425);
WIRE 16 -1 (-9375 5425)(-9375 5900);
WIRE 16 -1 (-9825 5750)(-9825 5900);
WIRE 16 -1 (-9375 5900)(-9825 5900);
WIRE 16 -1 (-9825 5900)(-10400 5900);
WIRE 16 -1 (-10400 5725)(-10400 5900);
WIRE 16 -1 (-9175 4925)(-9375 4925);
WIRE 16 -1 (-9375 4925)(-9375 5125);
WIRE 16 -1 (-9175 5125)(-9375 5125);
WIRE 16 -1 (-9975 5125)(-9375 5125);
WIRE 16 -1 (-9975 5125)(-9975 5425);
WIRE 16 -1 (-10400 5425)(-10400 5325);
WIRE 16 -1 (-10400 5525)(-10400 5425);
WIRE 16 -1 (-10400 5425)(-9975 5425);
FORCEPROP 2 LAST SIG_NAME PVCCINFAON_CPU0_VDD1
J 0
(-9935 5160);
DISPLAY 0.617021 (-9935 5160);
WIRE 16 -1 (-9550 4600)(-10100 4600);
WIRE 16 -1 (-10275 4675)(-9550 4675);
FORCEPROP 2 LAST SIG_NAME PVCCINFAON_CPU0_VREF
J 0
(-10160 4685);
DISPLAY 0.617021 (-10160 4685);
WIRE 16 -1 (-9550 4675)(-9550 4600);
FORCEPROP 0 LAST CDS_PHYS_NET_NAME PVCCINFAON_CPU0_VREF
J 0
(-9550 4625);
PAINT MONO (-9550 4625);
DISPLAY INVISIBLE (-9550 4625);
WIRE 16 -1 (-9550 4675)(-9175 4675);
WIRE 16 -1 (-9175 4775)(-10275 4775);
FORCEPROP 2 LAST SIG_NAME PVCCINFAON_CPU0_ACSP1
J 0
(-10160 4785);
DISPLAY 0.617021 (-10160 4785);
WIRE 16 -1 (-9175 4275)(-10275 4275);
FORCEPROP 2 LAST SIG_NAME PVCCINFAON_CPU0_ATSEN
J 0
(-10160 4285);
DISPLAY 0.617021 (-10160 4285);
WIRE 16 -1 (-10875 4475)(-10875 4300);
WIRE 16 -1 (-9175 4475)(-10875 4475);
FORCEPROP 2 LAST SIG_NAME PVCCINFAON_CPU0_LSET1
J 0
(-10160 4485);
DISPLAY 0.617021 (-10160 4485);
WIRE 16 -1 (-9500 2625)(-9325 2625);
WIRE 16 -1 (-9500 3175)(-9500 2625);
WIRE 16 -1 (-10400 2925)(-10400 3175);
WIRE 16 -1 (-9500 3175)(-9875 3175);
WIRE 16 -1 (-9875 3000)(-9875 3175);
WIRE 16 -1 (-9175 4175)(-10275 4175);
FORCEPROP 2 LAST SIG_NAME PVCCINFAON_CPU0_APWM1
J 0
(-10160 4185);
DISPLAY 0.617021 (-10160 4185);
WIRE 16 -1 (-9325 2125)(-9550 2125);
WIRE 16 -1 (-9550 2125)(-9550 2325);
WIRE 16 -1 (-9550 2325)(-9325 2325);
WIRE 16 -1 (-9975 2325)(-9550 2325);
WIRE 16 -1 (-9975 2325)(-9975 2625);
WIRE 16 -1 (-10400 2625)(-10400 2525);
WIRE 16 -1 (-10400 2725)(-10400 2625);
WIRE 16 -1 (-10400 2625)(-9975 2625);
FORCEPROP 2 LAST SIG_NAME PVCCINFAON_CPU0_VDD2
J 0
(-9960 2360);
DISPLAY 0.617021 (-9960 2360);
WIRE 16 -1 (-9325 1975)(-10275 1975);
FORCEPROP 2 LAST SIG_NAME PVCCINFAON_CPU0_ACSP2
J 0
(-10160 1985);
DISPLAY 0.617021 (-10160 1985);
WIRE 16 -1 (-9575 1800)(-10125 1800);
WIRE 16 -1 (-10275 1875)(-9575 1875);
FORCEPROP 2 LAST SIG_NAME PVCCINFAON_CPU0_VREF
J 0
(-10160 1885);
DISPLAY 0.617021 (-10160 1885);
WIRE 16 -1 (-9575 1875)(-9575 1800);
FORCEPROP 0 LAST CDS_PHYS_NET_NAME PVCCINFAON_CPU0_VREF
J 0
(-9575 1825);
PAINT MONO (-9575 1825);
DISPLAY INVISIBLE (-9575 1825);
WIRE 16 -1 (-9575 1875)(-9325 1875);
WIRE 16 -1 (-9325 1475)(-10275 1475);
FORCEPROP 2 LAST SIG_NAME PVCCINFAON_CPU0_ATSEN
J 0
(-10160 1485);
DISPLAY 0.617021 (-10160 1485);
WIRE 16 -1 (-9325 1375)(-10275 1375);
FORCEPROP 2 LAST SIG_NAME PVCCINFAON_CPU0_APWM2
J 0
(-10160 1385);
DISPLAY 0.617021 (-10160 1385);
WIRE 16 -1 (-10900 1675)(-10900 1500);
WIRE 16 -1 (-9325 1675)(-10900 1675);
FORCEPROP 2 LAST SIG_NAME PVCCINFAON_CPU0_LSET2
J 0
(-10160 1685);
DISPLAY 0.617021 (-10160 1685);
DOT 1 (-9575 1875);
DOT 1 (-10400 2625);
DOT 1 (-10400 3175);
DOT 1 (-9875 3175);
DOT 1 (-9550 2325);
DOT 1 (-10400 5425);
DOT 1 (-10400 5900);
DOT 1 (-9825 5900);
DOT 1 (-9550 4675);
DOT 1 (-9375 5125);
DOT 1 (-8225 1425);
DOT 1 (-8225 1375);
DOT 1 (-8225 1475);
DOT 1 (-8275 2625);
DOT 1 (-8075 3125);
DOT 1 (-8225 4225);
DOT 1 (-8225 4175);
DOT 1 (-7675 2625);
DOT 1 (-7275 2625);
DOT 1 (-7675 3125);
DOT 1 (-7275 3125);
DOT 1 (-6875 2625);
DOT 1 (-6875 3125);
DOT 1 (-5975 1975);
DOT 1 (-5475 1975);
DOT 1 (-5050 1550);
DOT 1 (-5050 1975);
DOT 1 (-8225 4275);
DOT 1 (-8175 5425);
DOT 1 (-8075 5925);
DOT 1 (-7675 5425);
DOT 1 (-7275 5425);
DOT 1 (-7675 5925);
DOT 1 (-7275 5925);
DOT 1 (-6875 5425);
DOT 1 (-6875 5925);
DOT 1 (-6225 4775);
DOT 1 (-6100 4775);
DOT 1 (-5700 4350);
DOT 1 (-5275 4350);
DOT 1 (-5700 4775);
DOT 1 (-5275 4775);
DOT 1 (-5025 6100);
DOT 1 (-4575 1550);
DOT 1 (-4575 1975);
DOT 1 (-3750 2900);
DOT 1 (-3750 3350);
DOT 1 (-3750 3825);
DOT 1 (-3175 2900);
DOT 1 (-3175 3350);
DOT 1 (-3750 4275);
DOT 1 (-4275 6100);
DOT 1 (-3875 5700);
DOT 1 (-3875 6100);
FORCENOTE
PVCCINFAON_CPU0_PHASE2
(-9375 3275) 0;
DISPLAY LEFT (-9375 3275);
DISPLAY 1.021277 (-9375 3275);
PAINT WHITE (-9375 3275);
FORCENOTE
PVCCINFAON_CPU0_PHASE1
(-9375 6075) 0;
DISPLAY LEFT (-9375 6075);
DISPLAY 1.021277 (-9375 6075);
PAINT WHITE (-9375 6075);
FORCENOTE
DCR=0.17M OHM
(-6125 2050) 0;
DISPLAY LEFT (-6125 2050);
DISPLAY 1.021277 (-6125 2050);
FORCENOTE
ISAT=60A@100C
(-6125 2125) 0;
DISPLAY LEFT (-6125 2125);
DISPLAY 1.021277 (-6125 2125);
FORCENOTE
6.5*6.5*10.0
(-6125 2200) 0;
DISPLAY LEFT (-6125 2200);
DISPLAY 1.021277 (-6125 2200);
FORCENOTE
PGL6312.121AHLT 
(-6125 2275) 0;
DISPLAY LEFT (-6125 2275);
DISPLAY 1.021277 (-6125 2275);
FORCENOTE
ISAT=60A@100C
(-6175 4950) 0;
DISPLAY LEFT (-6175 4950);
DISPLAY 1.021277 (-6175 4950);
FORCENOTE
DCR=0.17M OHM
(-6175 4875) 0;
DISPLAY LEFT (-6175 4875);
DISPLAY 1.021277 (-6175 4875);
FORCENOTE
6.5*6.5*10.0
(-6175 5025) 0;
DISPLAY LEFT (-6175 5025);
DISPLAY 1.021277 (-6175 5025);
FORCENOTE
PGL6312.121AHLT 
(-6175 5100) 0;
DISPLAY LEFT (-6175 5100);
DISPLAY 1.021277 (-6175 5100);
FORCENOTE
APPLY TO ALL RAILS.
(-4675 1050) 0;
DISPLAY LEFT (-4675 1050);
DISPLAY 1.021277 (-4675 1050);
FORCENOTE
RENESAS RECOMMEND BLEEDER RESISTOR
(-4675 1200) 0;
DISPLAY LEFT (-4675 1200);
DISPLAY 1.021277 (-4675 1200);
FORCENOTE
(499OHM) TO ABSORB LEAKAGE FROM SPS.
(-4675 1125) 0;
DISPLAY LEFT (-4675 1125);
DISPLAY 1.021277 (-4675 1125);
FORCENOTE
ESR=9.5M OHM
(-4225 5650) 0;
DISPLAY LEFT (-4225 5650);
DISPLAY 0.638298 (-4225 5650);
FORCENOTE
ESR=9.5M OHM
(-3825 5650) 0;
DISPLAY LEFT (-3825 5650);
DISPLAY 0.638298 (-3825 5650);
FORCENOTE
DCR = 0.12M OHM
(-4225 6200) 0;
DISPLAY LEFT (-4225 6200);
DISPLAY 0.808511 (-4225 6200);
FORCENOTE
ISAT = 13A @ 100C
(-4225 6275) 0;
DISPLAY LEFT (-4225 6275);
DISPLAY 0.808511 (-4225 6275);
FORCENOTE
4.5*4.5*4.5
(-4225 6350) 0;
DISPLAY LEFT (-4225 6350);
DISPLAY 0.808511 (-4225 6350);
FORCENOTE
HCBS4545-101
(-4225 6425) 0;
DISPLAY LEFT (-4225 6425);
DISPLAY 0.808511 (-4225 6425);
QUIT
